FILE_TYPE = MACRO_DRAWING;
SET COLOR_WIRE YELLOW;
SET COLOR_PROP ORANGE;
SET COLOR_DOT WHITE;
SET COLOR_ARC YELLOW;
SET COLOR_BODY GREEN;
SET COLOR_NOTE PURPLE;
SET PROP_DISPLAY VALUE;
SET PAGE_NUMBER P70;
FORCEADD UNIVERSAL_GND..1
(-3525 -725);
FORCEPROP 3 LASTPIN (-3525 -675) SIG_NAME GND\g
J 0
(-3515 -665);
DISPLAY 0.659574 (-3515 -665);
PAINT MONO (-3515 -665);
DISPLAY INVISIBLE (-3515 -665);
FORCEPROP 2 LAST CDS_LIB logical_power
J 0
(-3525 -725);
PAINT MONO (-3525 -725);
DISPLAY INVISIBLE (-3525 -725);
FORCEPROP 1 LAST HDL_POWER GND
J 1
(-3500 -800);
DISPLAY 0.872340 (-3500 -800);
PAINT GREEN (-3500 -800);
DISPLAY INVISIBLE (-3500 -800);
FORCEPROP 1 LAST PATH I1
J 0
(-3450 -725);
DISPLAY 0.872340 (-3450 -725);
PAINT AQUA (-3450 -725);
DISPLAY INVISIBLE (-3450 -725);
FORCEADD SOCKET4677_AZIF0045P001C01CS..31
(-2075 1800);
FORCEPROP 1 LAST PART_NUMBER DGA^7000023
J 0
(-3125 4050);
DISPLAY 0.723404 (-3125 4050);
PAINT GREEN (-3125 4050);
DISPLAY INVISIBLE (-3125 4050);
FORCEPROP 2 LAST PART_TYPE SMLF
J 0
(-3125 4225);
DISPLAY 1.021277 (-3125 4225);
FORCEPROP 1 LAST MATERIAL IO
J 0
(-3125 3975);
DISPLAY 0.723404 (-3125 3975);
PAINT GREEN (-3125 3975);
FORCEPROP 2 LAST VALUE SOCKET4677_AZIF0045-P001C01CS
J 0
(-3125 4175);
DISPLAY 1.021277 (-3125 4175);
FORCEPROP 1 LAST $LOCATION U1
J 0
(-3125 4125);
DISPLAY 0.723404 (-3125 4125);
PAINT GREEN (-3125 4125);
FORCEPROP 0 LASTPIN (-875 -125) $PN EH42
J 0
(-865 -115);
DISPLAY 0.680851 (-865 -115);
PAINT MONO (-865 -115);
FORCEPROP 0 LASTPIN (-875 -25) $PN EH55
J 0
(-865 -15);
DISPLAY 0.680851 (-865 -15);
PAINT MONO (-865 -15);
FORCEPROP 0 LASTPIN (-875 25) $PN EH61
J 0
(-865 35);
DISPLAY 0.680851 (-865 35);
PAINT MONO (-865 35);
FORCEPROP 0 LASTPIN (-875 75) $PN EH67
J 0
(-865 85);
DISPLAY 0.680851 (-865 85);
PAINT MONO (-865 85);
FORCEPROP 0 LASTPIN (-875 175) $PN EH79
J 0
(-865 185);
DISPLAY 0.680851 (-865 185);
PAINT MONO (-865 185);
FORCEPROP 0 LASTPIN (-875 425) $PN EJ11
J 0
(-865 435);
DISPLAY 0.680851 (-865 435);
PAINT MONO (-865 435);
FORCEPROP 0 LASTPIN (-875 525) $PN EJ17
J 0
(-865 535);
DISPLAY 0.680851 (-865 535);
PAINT MONO (-865 535);
FORCEPROP 0 LASTPIN (-875 675) $PN EJ25
J 0
(-865 685);
DISPLAY 0.680851 (-865 685);
PAINT MONO (-865 685);
FORCEPROP 0 LASTPIN (-875 825) $PN EJ35
J 0
(-865 835);
DISPLAY 0.680851 (-865 835);
PAINT MONO (-865 835);
FORCEPROP 0 LASTPIN (-875 1125) $PN EJ54
J 0
(-865 1135);
DISPLAY 0.680851 (-865 1135);
PAINT MONO (-865 1135);
FORCEPROP 0 LASTPIN (-875 1275) $PN EJ62
J 0
(-865 1285);
DISPLAY 0.680851 (-865 1285);
PAINT MONO (-865 1285);
FORCEPROP 0 LASTPIN (-875 1375) $PN EJ68
J 0
(-865 1385);
DISPLAY 0.680851 (-865 1385);
PAINT MONO (-865 1385);
FORCEPROP 0 LASTPIN (-875 1425) $PN EJ72
J 0
(-865 1435);
DISPLAY 0.680851 (-865 1435);
PAINT MONO (-865 1435);
FORCEPROP 0 LASTPIN (-875 1825) $PN EK16
J 0
(-865 1835);
DISPLAY 0.680851 (-865 1835);
PAINT MONO (-865 1835);
FORCEPROP 0 LASTPIN (-875 1875) $PN EK20
J 0
(-865 1885);
DISPLAY 0.680851 (-865 1885);
PAINT MONO (-865 1885);
FORCEPROP 0 LASTPIN (-875 1975) $PN EK26
J 0
(-865 1985);
DISPLAY 0.680851 (-865 1985);
PAINT MONO (-865 1985);
FORCEPROP 0 LASTPIN (-875 2275) $PN EK44
J 0
(-865 2285);
DISPLAY 0.680851 (-865 2285);
PAINT MONO (-865 2285);
FORCEPROP 0 LASTPIN (-875 2375) $PN EK51
J 0
(-865 2385);
DISPLAY 0.680851 (-865 2385);
PAINT MONO (-865 2385);
FORCEPROP 0 LASTPIN (-875 2425) $PN EK53
J 0
(-865 2435);
DISPLAY 0.680851 (-865 2435);
PAINT MONO (-865 2435);
FORCEPROP 0 LASTPIN (-875 2525) $PN EK59
J 0
(-865 2535);
DISPLAY 0.680851 (-865 2535);
PAINT MONO (-865 2535);
FORCEPROP 0 LASTPIN (-875 2575) $PN EK63
J 0
(-865 2585);
DISPLAY 0.680851 (-865 2585);
PAINT MONO (-865 2585);
FORCEPROP 0 LASTPIN (-875 2725) $PN EK71
J 0
(-865 2735);
DISPLAY 0.680851 (-865 2735);
PAINT MONO (-865 2735);
FORCEPROP 0 LASTPIN (-875 2825) $PN EK77
J 0
(-865 2835);
DISPLAY 0.680851 (-865 2835);
PAINT MONO (-865 2835);
FORCEPROP 0 LASTPIN (-875 2875) $PN EK79
J 0
(-865 2885);
DISPLAY 0.680851 (-865 2885);
PAINT MONO (-865 2885);
FORCEPROP 0 LASTPIN (-875 2925) $PN EK83
J 0
(-865 2935);
DISPLAY 0.680851 (-865 2935);
PAINT MONO (-865 2935);
FORCEPROP 0 LASTPIN (-875 2975) $PN EK89
J 0
(-865 2985);
DISPLAY 0.680851 (-865 2985);
PAINT MONO (-865 2985);
FORCEPROP 0 LASTPIN (-875 3225) $PN EL15
J 0
(-865 3235);
DISPLAY 0.680851 (-865 3235);
PAINT MONO (-865 3235);
FORCEPROP 0 LASTPIN (-875 3525) $PN EL52
J 0
(-865 3535);
DISPLAY 0.680851 (-865 3535);
PAINT MONO (-865 3535);
FORCEPROP 0 LASTPIN (-875 3575) $PN EL58
J 0
(-865 3585);
DISPLAY 0.680851 (-865 3585);
PAINT MONO (-865 3585);
FORCEPROP 0 LASTPIN (-875 3125) $PN EL7
J 0
(-865 3135);
DISPLAY 0.680851 (-865 3135);
PAINT MONO (-865 3135);
FORCEPROP 0 LASTPIN (-875 3675) $PN EL70
J 0
(-865 3685);
DISPLAY 0.680851 (-865 3685);
PAINT MONO (-865 3685);
FORCEPROP 0 LASTPIN (-875 3725) $PN EL72
J 0
(-865 3735);
DISPLAY 0.680851 (-865 3735);
PAINT MONO (-865 3735);
FORCEPROP 0 LASTPIN (-3275 -175) $PN EL86
J 2
(-3285 -165);
DISPLAY 0.680851 (-3285 -165);
PAINT MONO (-3285 -165);
FORCEPROP 0 LASTPIN (-875 3175) $PN EL9
J 0
(-865 3185);
DISPLAY 0.680851 (-865 3185);
PAINT MONO (-865 3185);
FORCEPROP 0 LASTPIN (-3275 -25) $PN EM49
J 2
(-3285 -15);
DISPLAY 0.680851 (-3285 -15);
PAINT MONO (-3285 -15);
FORCEPROP 0 LASTPIN (-3275 75) $PN EM79
J 2
(-3285 85);
DISPLAY 0.680851 (-3285 85);
PAINT MONO (-3285 85);
FORCEPROP 0 LASTPIN (-875 -175) $PN EH36
J 0
(-865 -165);
DISPLAY 0.680851 (-865 -165);
PAINT MONO (-865 -165);
FORCEPROP 0 LASTPIN (-875 -75) $PN EH49
J 0
(-865 -65);
DISPLAY 0.680851 (-865 -65);
PAINT MONO (-865 -65);
FORCEPROP 0 LASTPIN (-875 125) $PN EH73
J 0
(-865 135);
DISPLAY 0.680851 (-865 135);
PAINT MONO (-865 135);
FORCEPROP 0 LASTPIN (-875 225) $PN EH81
J 0
(-865 235);
DISPLAY 0.680851 (-865 235);
PAINT MONO (-865 235);
FORCEPROP 0 LASTPIN (-875 275) $PN EH83
J 0
(-865 285);
DISPLAY 0.680851 (-865 285);
PAINT MONO (-865 285);
FORCEPROP 0 LASTPIN (-875 475) $PN EJ13
J 0
(-865 485);
DISPLAY 0.680851 (-865 485);
PAINT MONO (-865 485);
FORCEPROP 0 LASTPIN (-875 575) $PN EJ19
J 0
(-865 585);
DISPLAY 0.680851 (-865 585);
PAINT MONO (-865 585);
FORCEPROP 0 LASTPIN (-3275 975) $PN EN39
J 2
(-3285 985);
DISPLAY 0.680851 (-3285 985);
PAINT MONO (-3285 985);
FORCEPROP 0 LASTPIN (-875 625) $PN EJ23
J 0
(-865 635);
DISPLAY 0.680851 (-865 635);
PAINT MONO (-865 635);
FORCEPROP 0 LASTPIN (-875 725) $PN EJ29
J 0
(-865 735);
DISPLAY 0.680851 (-865 735);
PAINT MONO (-865 735);
FORCEPROP 0 LASTPIN (-875 775) $PN EJ31
J 0
(-865 785);
DISPLAY 0.680851 (-865 785);
PAINT MONO (-865 785);
FORCEPROP 0 LASTPIN (-875 875) $PN EJ37
J 0
(-865 885);
DISPLAY 0.680851 (-865 885);
PAINT MONO (-865 885);
FORCEPROP 0 LASTPIN (-875 925) $PN EJ41
J 0
(-865 935);
DISPLAY 0.680851 (-865 935);
PAINT MONO (-865 935);
FORCEPROP 0 LASTPIN (-875 975) $PN EJ43
J 0
(-865 985);
DISPLAY 0.680851 (-865 985);
PAINT MONO (-865 985);
FORCEPROP 0 LASTPIN (-875 1025) $PN EJ48
J 0
(-865 1035);
DISPLAY 0.680851 (-865 1035);
PAINT MONO (-865 1035);
FORCEPROP 0 LASTPIN (-875 1075) $PN EJ50
J 0
(-865 1085);
DISPLAY 0.680851 (-865 1085);
PAINT MONO (-865 1085);
FORCEPROP 0 LASTPIN (-3275 1425) $PN EN58
J 2
(-3285 1435);
DISPLAY 0.680851 (-3285 1435);
PAINT MONO (-3285 1435);
FORCEPROP 0 LASTPIN (-3275 1475) $PN EN60
J 2
(-3285 1485);
DISPLAY 0.680851 (-3285 1485);
PAINT MONO (-3285 1485);
FORCEPROP 0 LASTPIN (-3275 1525) $PN EN62
J 2
(-3285 1535);
DISPLAY 0.680851 (-3285 1535);
PAINT MONO (-3285 1535);
FORCEPROP 0 LASTPIN (-875 1175) $PN EJ56
J 0
(-865 1185);
DISPLAY 0.680851 (-865 1185);
PAINT MONO (-865 1185);
FORCEPROP 0 LASTPIN (-3275 1625) $PN EN66
J 2
(-3285 1635);
DISPLAY 0.680851 (-3285 1635);
PAINT MONO (-3285 1635);
FORCEPROP 0 LASTPIN (-3275 1675) $PN EN72
J 2
(-3285 1685);
DISPLAY 0.680851 (-3285 1685);
PAINT MONO (-3285 1685);
FORCEPROP 0 LASTPIN (-875 1225) $PN EJ60
J 0
(-865 1235);
DISPLAY 0.680851 (-865 1235);
PAINT MONO (-865 1235);
FORCEPROP 0 LASTPIN (-875 1325) $PN EJ66
J 0
(-865 1335);
DISPLAY 0.680851 (-865 1335);
PAINT MONO (-865 1335);
FORCEPROP 0 LASTPIN (-875 325) $PN EJ7
J 0
(-865 335);
DISPLAY 0.680851 (-865 335);
PAINT MONO (-865 335);
FORCEPROP 0 LASTPIN (-3275 1825) $PN EN88
J 2
(-3285 1835);
DISPLAY 0.680851 (-3285 1835);
PAINT MONO (-3285 1835);
FORCEPROP 0 LASTPIN (-3275 225) $PN EN9
J 2
(-3285 235);
DISPLAY 0.680851 (-3285 235);
PAINT MONO (-3285 235);
FORCEPROP 0 LASTPIN (-875 1475) $PN EJ74
J 0
(-865 1485);
DISPLAY 0.680851 (-865 1485);
PAINT MONO (-865 1485);
FORCEPROP 0 LASTPIN (-875 1525) $PN EJ78
J 0
(-865 1535);
DISPLAY 0.680851 (-865 1535);
PAINT MONO (-865 1535);
FORCEPROP 0 LASTPIN (-875 1575) $PN EJ88
J 0
(-865 1585);
DISPLAY 0.680851 (-865 1585);
PAINT MONO (-865 1585);
FORCEPROP 0 LASTPIN (-875 375) $PN EJ9
J 0
(-865 385);
DISPLAY 0.680851 (-865 385);
PAINT MONO (-865 385);
FORCEPROP 0 LASTPIN (-875 1725) $PN EK10
J 0
(-865 1735);
DISPLAY 0.680851 (-865 1735);
PAINT MONO (-865 1735);
FORCEPROP 0 LASTPIN (-3275 1925) $PN EP69
J 2
(-3285 1935);
DISPLAY 0.680851 (-3285 1935);
PAINT MONO (-3285 1935);
FORCEPROP 0 LASTPIN (-3275 1975) $PN EP71
J 2
(-3285 1985);
DISPLAY 0.680851 (-3285 1985);
PAINT MONO (-3285 1985);
FORCEPROP 0 LASTPIN (-3275 2025) $PN EP77
J 2
(-3285 2035);
DISPLAY 0.680851 (-3285 2035);
PAINT MONO (-3285 2035);
FORCEPROP 0 LASTPIN (-875 1775) $PN EK14
J 0
(-865 1785);
DISPLAY 0.680851 (-865 1785);
PAINT MONO (-865 1785);
FORCEPROP 0 LASTPIN (-3275 2275) $PN ER15
J 2
(-3285 2285);
DISPLAY 0.680851 (-3285 2285);
PAINT MONO (-3285 2285);
FORCEPROP 0 LASTPIN (-3275 2325) $PN ER21
J 2
(-3285 2335);
DISPLAY 0.680851 (-3285 2335);
PAINT MONO (-3285 2335);
FORCEPROP 0 LASTPIN (-875 1625) $PN EK2
J 0
(-865 1635);
DISPLAY 0.680851 (-865 1635);
PAINT MONO (-865 1635);
FORCEPROP 0 LASTPIN (-875 1925) $PN EK22
J 0
(-865 1935);
DISPLAY 0.680851 (-865 1935);
PAINT MONO (-865 1935);
FORCEPROP 0 LASTPIN (-875 2025) $PN EK28
J 0
(-865 2035);
DISPLAY 0.680851 (-865 2035);
PAINT MONO (-865 2035);
FORCEPROP 0 LASTPIN (-875 2075) $PN EK32
J 0
(-865 2085);
DISPLAY 0.680851 (-865 2085);
PAINT MONO (-865 2085);
FORCEPROP 0 LASTPIN (-3275 2475) $PN ER39
J 2
(-3285 2485);
DISPLAY 0.680851 (-3285 2485);
PAINT MONO (-3285 2485);
FORCEPROP 0 LASTPIN (-875 2125) $PN EK34
J 0
(-865 2135);
DISPLAY 0.680851 (-865 2135);
PAINT MONO (-865 2135);
FORCEPROP 0 LASTPIN (-3275 2525) $PN ER52
J 2
(-3285 2535);
DISPLAY 0.680851 (-3285 2535);
PAINT MONO (-3285 2535);
FORCEPROP 0 LASTPIN (-875 2175) $PN EK38
J 0
(-865 2185);
DISPLAY 0.680851 (-865 2185);
PAINT MONO (-865 2185);
FORCEPROP 0 LASTPIN (-875 1675) $PN EK4
J 0
(-865 1685);
DISPLAY 0.680851 (-865 1685);
PAINT MONO (-865 1685);
FORCEPROP 0 LASTPIN (-3275 2575) $PN ER58
J 2
(-3285 2585);
DISPLAY 0.680851 (-3285 2585);
PAINT MONO (-3285 2585);
FORCEPROP 0 LASTPIN (-3275 2625) $PN ER64
J 2
(-3285 2635);
DISPLAY 0.680851 (-3285 2635);
PAINT MONO (-3285 2635);
FORCEPROP 0 LASTPIN (-875 2225) $PN EK40
J 0
(-865 2235);
DISPLAY 0.680851 (-865 2235);
PAINT MONO (-865 2235);
FORCEPROP 0 LASTPIN (-875 2325) $PN EK47
J 0
(-865 2335);
DISPLAY 0.680851 (-865 2335);
PAINT MONO (-865 2335);
FORCEPROP 0 LASTPIN (-875 2475) $PN EK57
J 0
(-865 2485);
DISPLAY 0.680851 (-865 2485);
PAINT MONO (-865 2485);
FORCEPROP 0 LASTPIN (-875 2625) $PN EK65
J 0
(-865 2635);
DISPLAY 0.680851 (-865 2635);
PAINT MONO (-865 2635);
FORCEPROP 0 LASTPIN (-875 2675) $PN EK69
J 0
(-865 2685);
DISPLAY 0.680851 (-865 2685);
PAINT MONO (-865 2685);
FORCEPROP 0 LASTPIN (-875 2775) $PN EK75
J 0
(-865 2785);
DISPLAY 0.680851 (-865 2785);
PAINT MONO (-865 2785);
FORCEPROP 0 LASTPIN (-875 3275) $PN EL21
J 0
(-865 3285);
DISPLAY 0.680851 (-865 3285);
PAINT MONO (-865 3285);
FORCEPROP 0 LASTPIN (-3275 2225) $PN ER9
J 2
(-3285 2235);
DISPLAY 0.680851 (-3285 2235);
PAINT MONO (-3285 2235);
FORCEPROP 0 LASTPIN (-875 3325) $PN EL27
J 0
(-865 3335);
DISPLAY 0.680851 (-865 3335);
PAINT MONO (-865 3335);
FORCEPROP 0 LASTPIN (-3275 3025) $PN ET14
J 2
(-3285 3035);
DISPLAY 0.680851 (-3285 3035);
PAINT MONO (-3285 3035);
FORCEPROP 0 LASTPIN (-875 3025) $PN EL3
J 0
(-865 3035);
DISPLAY 0.680851 (-865 3035);
PAINT MONO (-865 3035);
FORCEPROP 0 LASTPIN (-3275 3125) $PN ET20
J 2
(-3285 3135);
DISPLAY 0.680851 (-3285 3135);
PAINT MONO (-3285 3135);
FORCEPROP 0 LASTPIN (-875 3375) $PN EL33
J 0
(-865 3385);
DISPLAY 0.680851 (-865 3385);
PAINT MONO (-865 3385);
FORCEPROP 0 LASTPIN (-3275 3225) $PN ET26
J 2
(-3285 3235);
DISPLAY 0.680851 (-3285 3235);
PAINT MONO (-3285 3235);
FORCEPROP 0 LASTPIN (-875 3425) $PN EL39
J 0
(-865 3435);
DISPLAY 0.680851 (-865 3435);
PAINT MONO (-865 3435);
FORCEPROP 0 LASTPIN (-3275 3325) $PN ET32
J 2
(-3285 3335);
DISPLAY 0.680851 (-3285 3335);
PAINT MONO (-3285 3335);
FORCEPROP 0 LASTPIN (-875 3475) $PN EL45
J 0
(-865 3485);
DISPLAY 0.680851 (-865 3485);
PAINT MONO (-865 3485);
FORCEPROP 0 LASTPIN (-875 3075) $PN EL5
J 0
(-865 3085);
DISPLAY 0.680851 (-865 3085);
PAINT MONO (-865 3085);
FORCEPROP 0 LASTPIN (-875 3625) $PN EL64
J 0
(-865 3635);
DISPLAY 0.680851 (-865 3635);
PAINT MONO (-865 3635);
FORCEPROP 0 LASTPIN (-875 3775) $PN EL76
J 0
(-865 3785);
DISPLAY 0.680851 (-865 3785);
PAINT MONO (-865 3785);
FORCEPROP 0 LASTPIN (-3275 3675) $PN ET53
J 2
(-3285 3685);
DISPLAY 0.680851 (-3285 3685);
PAINT MONO (-3285 3685);
FORCEPROP 0 LASTPIN (-3275 -75) $PN EM42
J 2
(-3285 -65);
DISPLAY 0.680851 (-3285 -65);
PAINT MONO (-3285 -65);
FORCEPROP 0 LASTPIN (-3275 3775) $PN ET59
J 2
(-3285 3785);
DISPLAY 0.680851 (-3285 3785);
PAINT MONO (-3285 3785);
FORCEPROP 0 LASTPIN (-3275 25) $PN EM73
J 2
(-3285 35);
DISPLAY 0.680851 (-3285 35);
PAINT MONO (-3285 35);
FORCEPROP 0 LASTPIN (-3275 -125) $PN EM8
J 2
(-3285 -115);
DISPLAY 0.680851 (-3285 -115);
PAINT MONO (-3285 -115);
FORCEPROP 0 LASTPIN (-3275 125) $PN EM81
J 2
(-3285 135);
DISPLAY 0.680851 (-3285 135);
PAINT MONO (-3285 135);
FORCEPROP 0 LASTPIN (-3275 175) $PN EM83
J 2
(-3285 185);
DISPLAY 0.680851 (-3285 185);
PAINT MONO (-3285 185);
FORCEPROP 0 LASTPIN (-3275 275) $PN EN11
J 2
(-3285 285);
DISPLAY 0.680851 (-3285 285);
PAINT MONO (-3285 285);
FORCEPROP 0 LASTPIN (-3275 325) $PN EN13
J 2
(-3285 335);
DISPLAY 0.680851 (-3285 335);
PAINT MONO (-3285 335);
FORCEPROP 0 LASTPIN (-3275 375) $PN EN15
J 2
(-3285 385);
DISPLAY 0.680851 (-3285 385);
PAINT MONO (-3285 385);
FORCEPROP 0 LASTPIN (-3275 425) $PN EN17
J 2
(-3285 435);
DISPLAY 0.680851 (-3285 435);
PAINT MONO (-3285 435);
FORCEPROP 0 LASTPIN (-3275 475) $PN EN19
J 2
(-3285 485);
DISPLAY 0.680851 (-3285 485);
PAINT MONO (-3285 485);
FORCEPROP 0 LASTPIN (-3275 525) $PN EN21
J 2
(-3285 535);
DISPLAY 0.680851 (-3285 535);
PAINT MONO (-3285 535);
FORCEPROP 0 LASTPIN (-3275 575) $PN EN23
J 2
(-3285 585);
DISPLAY 0.680851 (-3285 585);
PAINT MONO (-3285 585);
FORCEPROP 0 LASTPIN (-3275 625) $PN EN25
J 2
(-3285 635);
DISPLAY 0.680851 (-3285 635);
PAINT MONO (-3285 635);
FORCEPROP 0 LASTPIN (-3275 675) $PN EN27
J 2
(-3285 685);
DISPLAY 0.680851 (-3285 685);
PAINT MONO (-3285 685);
FORCEPROP 0 LASTPIN (-3275 725) $PN EN29
J 2
(-3285 735);
DISPLAY 0.680851 (-3285 735);
PAINT MONO (-3285 735);
FORCEPROP 0 LASTPIN (-3275 775) $PN EN31
J 2
(-3285 785);
DISPLAY 0.680851 (-3285 785);
PAINT MONO (-3285 785);
FORCEPROP 0 LASTPIN (-3275 825) $PN EN33
J 2
(-3285 835);
DISPLAY 0.680851 (-3285 835);
PAINT MONO (-3285 835);
FORCEPROP 0 LASTPIN (-3275 875) $PN EN35
J 2
(-3285 885);
DISPLAY 0.680851 (-3285 885);
PAINT MONO (-3285 885);
FORCEPROP 0 LASTPIN (-3275 925) $PN EN37
J 2
(-3285 935);
DISPLAY 0.680851 (-3285 935);
PAINT MONO (-3285 935);
FORCEPROP 0 LASTPIN (-3275 1025) $PN EN41
J 2
(-3285 1035);
DISPLAY 0.680851 (-3285 1035);
PAINT MONO (-3285 1035);
FORCEPROP 0 LASTPIN (-3275 1075) $PN EN43
J 2
(-3285 1085);
DISPLAY 0.680851 (-3285 1085);
PAINT MONO (-3285 1085);
FORCEPROP 0 LASTPIN (-3275 1125) $PN EN45
J 2
(-3285 1135);
DISPLAY 0.680851 (-3285 1135);
PAINT MONO (-3285 1135);
FORCEPROP 0 LASTPIN (-3275 1175) $PN EN48
J 2
(-3285 1185);
DISPLAY 0.680851 (-3285 1185);
PAINT MONO (-3285 1185);
FORCEPROP 0 LASTPIN (-3275 1225) $PN EN50
J 2
(-3285 1235);
DISPLAY 0.680851 (-3285 1235);
PAINT MONO (-3285 1235);
FORCEPROP 0 LASTPIN (-3275 1275) $PN EN52
J 2
(-3285 1285);
DISPLAY 0.680851 (-3285 1285);
PAINT MONO (-3285 1285);
FORCEPROP 0 LASTPIN (-3275 1325) $PN EN54
J 2
(-3285 1335);
DISPLAY 0.680851 (-3285 1335);
PAINT MONO (-3285 1335);
FORCEPROP 0 LASTPIN (-3275 1375) $PN EN56
J 2
(-3285 1385);
DISPLAY 0.680851 (-3285 1385);
PAINT MONO (-3285 1385);
FORCEPROP 0 LASTPIN (-3275 1575) $PN EN64
J 2
(-3285 1585);
DISPLAY 0.680851 (-3285 1585);
PAINT MONO (-3285 1585);
FORCEPROP 0 LASTPIN (-3275 1725) $PN EN78
J 2
(-3285 1735);
DISPLAY 0.680851 (-3285 1735);
PAINT MONO (-3285 1735);
FORCEPROP 0 LASTPIN (-3275 1775) $PN EN80
J 2
(-3285 1785);
DISPLAY 0.680851 (-3285 1785);
PAINT MONO (-3285 1785);
FORCEPROP 0 LASTPIN (-3275 1875) $PN EP67
J 2
(-3285 1885);
DISPLAY 0.680851 (-3285 1885);
PAINT MONO (-3285 1885);
FORCEPROP 0 LASTPIN (-3275 2075) $PN EP83
J 2
(-3285 2085);
DISPLAY 0.680851 (-3285 2085);
PAINT MONO (-3285 2085);
FORCEPROP 0 LASTPIN (-3275 2375) $PN ER27
J 2
(-3285 2385);
DISPLAY 0.680851 (-3285 2385);
PAINT MONO (-3285 2385);
FORCEPROP 0 LASTPIN (-3275 2425) $PN ER33
J 2
(-3285 2435);
DISPLAY 0.680851 (-3285 2435);
PAINT MONO (-3285 2435);
FORCEPROP 0 LASTPIN (-3275 2125) $PN ER5
J 2
(-3285 2135);
DISPLAY 0.680851 (-3285 2135);
PAINT MONO (-3285 2135);
FORCEPROP 0 LASTPIN (-3275 2175) $PN ER7
J 2
(-3285 2185);
DISPLAY 0.680851 (-3285 2185);
PAINT MONO (-3285 2185);
FORCEPROP 0 LASTPIN (-3275 2675) $PN ER70
J 2
(-3285 2685);
DISPLAY 0.680851 (-3285 2685);
PAINT MONO (-3285 2685);
FORCEPROP 0 LASTPIN (-3275 2725) $PN ER74
J 2
(-3285 2735);
DISPLAY 0.680851 (-3285 2735);
PAINT MONO (-3285 2735);
FORCEPROP 0 LASTPIN (-3275 2775) $PN ER78
J 2
(-3285 2785);
DISPLAY 0.680851 (-3285 2785);
PAINT MONO (-3285 2785);
FORCEPROP 0 LASTPIN (-3275 2825) $PN ER80
J 2
(-3285 2835);
DISPLAY 0.680851 (-3285 2835);
PAINT MONO (-3285 2835);
FORCEPROP 0 LASTPIN (-3275 2875) $PN ER84
J 2
(-3285 2885);
DISPLAY 0.680851 (-3285 2885);
PAINT MONO (-3285 2885);
FORCEPROP 0 LASTPIN (-3275 2925) $PN ER86
J 2
(-3285 2935);
DISPLAY 0.680851 (-3285 2935);
PAINT MONO (-3285 2935);
FORCEPROP 0 LASTPIN (-3275 2975) $PN ET10
J 2
(-3285 2985);
DISPLAY 0.680851 (-3285 2985);
PAINT MONO (-3285 2985);
FORCEPROP 0 LASTPIN (-3275 3075) $PN ET16
J 2
(-3285 3085);
DISPLAY 0.680851 (-3285 3085);
PAINT MONO (-3285 3085);
FORCEPROP 0 LASTPIN (-3275 3175) $PN ET22
J 2
(-3285 3185);
DISPLAY 0.680851 (-3285 3185);
PAINT MONO (-3285 3185);
FORCEPROP 0 LASTPIN (-3275 3275) $PN ET28
J 2
(-3285 3285);
DISPLAY 0.680851 (-3285 3285);
PAINT MONO (-3285 3285);
FORCEPROP 0 LASTPIN (-3275 3375) $PN ET34
J 2
(-3285 3385);
DISPLAY 0.680851 (-3285 3385);
PAINT MONO (-3285 3385);
FORCEPROP 0 LASTPIN (-3275 3425) $PN ET38
J 2
(-3285 3435);
DISPLAY 0.680851 (-3285 3435);
PAINT MONO (-3285 3435);
FORCEPROP 0 LASTPIN (-3275 3725) $PN ET57
J 2
(-3285 3735);
DISPLAY 0.680851 (-3285 3735);
PAINT MONO (-3285 3735);
FORCEPROP 0 LASTPIN (-3275 3475) $PN ER41
J 2
(-3285 3485);
DISPLAY 0.680851 (-3285 3485);
PAINT MONO (-3285 3485);
FORCEPROP 0 LASTPIN (-3275 3525) $PN ER43
J 2
(-3285 3535);
DISPLAY 0.680851 (-3285 3535);
PAINT MONO (-3285 3535);
FORCEPROP 0 LASTPIN (-3275 3575) $PN ER48
J 2
(-3285 3585);
DISPLAY 0.680851 (-3285 3585);
PAINT MONO (-3285 3585);
FORCEPROP 0 LASTPIN (-3275 3625) $PN ER50
J 2
(-3285 3635);
DISPLAY 0.680851 (-3285 3635);
PAINT MONO (-3285 3635);
FORCEPROP 2 LAST CDS_LIB pure_quanta
J 0
(-2075 1800);
DISPLAY INVISIBLE (-2075 1800);
FORCEPROP 1 LAST NEEDS_NO_SIZE TRUE
J 0
(-2075 1800);
DISPLAY 0.723404 (-2075 1800);
PAINT GREEN (-2075 1800);
DISPLAY INVISIBLE (-2075 1800);
FORCEPROP 1 LAST CDS_LMAN_SYM_OUTLINE -1050,2150,1050,-2100
J 0
(-2075 1800);
DISPLAY 0.468085 (-2075 1800);
PAINT GREEN (-2075 1800);
DISPLAY INVISIBLE (-2075 1800);
FORCEPROP 0 LAST CDS_LOCATION U1
J 0
(-3125 4275);
DISPLAY 1.021277 (-3125 4275);
DISPLAY INVISIBLE (-3125 4275);
FORCEPROP 0 LAST $SEC 31
J 0
(-3125 4275);
DISPLAY 0.680851 (-3125 4275);
PAINT MONO (-3125 4275);
DISPLAY INVISIBLE (-3125 4275);
FORCEPROP 2 LAST CDS_SEC 31
J 0
(-3125 4275);
DISPLAY 1.021277 (-3125 4275);
DISPLAY INVISIBLE (-3125 4275);
FORCEPROP 1 LAST PATH I2
J 0
(-2075 1800);
DISPLAY 0.723404 (-2075 1800);
PAINT GREEN (-2075 1800);
DISPLAY INVISIBLE (-2075 1800);
FORCEADD UNIVERSAL_GND..1
(-625 -725);
FORCEPROP 3 LASTPIN (-625 -675) SIG_NAME GND\g
J 0
(-615 -665);
DISPLAY 0.659574 (-615 -665);
PAINT MONO (-615 -665);
DISPLAY INVISIBLE (-615 -665);
FORCEPROP 2 LAST CDS_LIB logical_power
J 0
(-625 -725);
PAINT MONO (-625 -725);
DISPLAY INVISIBLE (-625 -725);
FORCEPROP 1 LAST HDL_POWER GND
J 1
(-600 -800);
DISPLAY 0.872340 (-600 -800);
PAINT GREEN (-600 -800);
DISPLAY INVISIBLE (-600 -800);
FORCEPROP 1 LAST PATH I3
J 0
(-550 -725);
DISPLAY 0.872340 (-550 -725);
PAINT AQUA (-550 -725);
DISPLAY INVISIBLE (-550 -725);
FORCEADD UNIVERSAL_GND..1
(-475 -725);
FORCEPROP 3 LASTPIN (-475 -675) SIG_NAME GND\g
J 0
(-465 -665);
DISPLAY 0.659574 (-465 -665);
PAINT MONO (-465 -665);
DISPLAY INVISIBLE (-465 -665);
FORCEPROP 2 LAST CDS_LIB logical_power
J 0
(-475 -725);
PAINT MONO (-475 -725);
DISPLAY INVISIBLE (-475 -725);
FORCEPROP 1 LAST HDL_POWER GND
J 1
(-450 -800);
DISPLAY 0.872340 (-450 -800);
PAINT GREEN (-450 -800);
DISPLAY INVISIBLE (-450 -800);
FORCEPROP 1 LAST PATH I4
J 0
(-400 -725);
DISPLAY 0.872340 (-400 -725);
PAINT AQUA (-400 -725);
DISPLAY INVISIBLE (-400 -725);
FORCEADD SOCKET4677_AZIF0045P001C01CS..32
(975 1800);
FORCEPROP 1 LAST PART_NUMBER DGA^7000023
J 0
(-75 4050);
DISPLAY 0.723404 (-75 4050);
PAINT GREEN (-75 4050);
DISPLAY INVISIBLE (-75 4050);
FORCEPROP 2 LAST PART_TYPE SMLF
J 0
(-75 4225);
DISPLAY 1.021277 (-75 4225);
FORCEPROP 1 LAST MATERIAL IO
J 0
(-75 3975);
DISPLAY 0.723404 (-75 3975);
PAINT GREEN (-75 3975);
FORCEPROP 2 LAST VALUE SOCKET4677_AZIF0045-P001C01CS
J 0
(-75 4175);
DISPLAY 1.021277 (-75 4175);
FORCEPROP 1 LAST $LOCATION U1
J 0
(-75 4125);
DISPLAY 0.723404 (-75 4125);
PAINT GREEN (-75 4125);
FORCEPROP 0 LASTPIN (2175 425) $PN DY12
J 0
(2185 435);
DISPLAY 0.680851 (2185 435);
PAINT MONO (2185 435);
FORCEPROP 0 LASTPIN (2175 475) $PN DY16
J 0
(2185 485);
DISPLAY 0.680851 (2185 485);
PAINT MONO (2185 485);
FORCEPROP 0 LASTPIN (2175 325) $PN DY4
J 0
(2185 335);
DISPLAY 0.680851 (2185 335);
PAINT MONO (2185 335);
FORCEPROP 0 LASTPIN (2175 525) $PN DY42
J 0
(2185 535);
DISPLAY 0.680851 (2185 535);
PAINT MONO (2185 535);
FORCEPROP 0 LASTPIN (2175 775) $PN EA39
J 0
(2185 785);
DISPLAY 0.680851 (2185 785);
PAINT MONO (2185 785);
FORCEPROP 0 LASTPIN (2175 825) $PN EA45
J 0
(2185 835);
DISPLAY 0.680851 (2185 835);
PAINT MONO (2185 835);
FORCEPROP 0 LASTPIN (2175 875) $PN EA52
J 0
(2185 885);
DISPLAY 0.680851 (2185 885);
PAINT MONO (2185 885);
FORCEPROP 0 LASTPIN (2175 925) $PN EA58
J 0
(2185 935);
DISPLAY 0.680851 (2185 935);
PAINT MONO (2185 935);
FORCEPROP 0 LASTPIN (2175 975) $PN EA64
J 0
(2185 985);
DISPLAY 0.680851 (2185 985);
PAINT MONO (2185 985);
FORCEPROP 0 LASTPIN (2175 1475) $PN EB16
J 0
(2185 1485);
DISPLAY 0.680851 (2185 1485);
PAINT MONO (2185 1485);
FORCEPROP 0 LASTPIN (2175 1525) $PN EB20
J 0
(2185 1535);
DISPLAY 0.680851 (2185 1535);
PAINT MONO (2185 1535);
FORCEPROP 0 LASTPIN (2175 1625) $PN EB26
J 0
(2185 1635);
DISPLAY 0.680851 (2185 1635);
PAINT MONO (2185 1635);
FORCEPROP 0 LASTPIN (2175 1775) $PN EB34
J 0
(2185 1785);
DISPLAY 0.680851 (2185 1785);
PAINT MONO (2185 1785);
FORCEPROP 0 LASTPIN (2175 1325) $PN EB4
J 0
(2185 1335);
DISPLAY 0.680851 (2185 1335);
PAINT MONO (2185 1335);
FORCEPROP 0 LASTPIN (2175 1925) $PN EB44
J 0
(2185 1935);
DISPLAY 0.680851 (2185 1935);
PAINT MONO (2185 1935);
FORCEPROP 0 LASTPIN (2175 2025) $PN EB51
J 0
(2185 2035);
DISPLAY 0.680851 (2185 2035);
PAINT MONO (2185 2035);
FORCEPROP 0 LASTPIN (2175 2075) $PN EB53
J 0
(2185 2085);
DISPLAY 0.680851 (2185 2085);
PAINT MONO (2185 2085);
FORCEPROP 0 LASTPIN (2175 2175) $PN EB59
J 0
(2185 2185);
DISPLAY 0.680851 (2185 2185);
PAINT MONO (2185 2185);
FORCEPROP 0 LASTPIN (2175 2225) $PN EB63
J 0
(2185 2235);
DISPLAY 0.680851 (2185 2235);
PAINT MONO (2185 2235);
FORCEPROP 0 LASTPIN (2175 2625) $PN EB91
J 0
(2185 2635);
DISPLAY 0.680851 (2185 2635);
PAINT MONO (2185 2635);
FORCEPROP 0 LASTPIN (2175 2975) $PN EC25
J 0
(2185 2985);
DISPLAY 0.680851 (2185 2985);
PAINT MONO (2185 2985);
FORCEPROP 0 LASTPIN (2175 3125) $PN EC35
J 0
(2185 3135);
DISPLAY 0.680851 (2185 3135);
PAINT MONO (2185 3135);
FORCEPROP 0 LASTPIN (2175 2725) $PN EC5
J 0
(2185 2735);
DISPLAY 0.680851 (2185 2735);
PAINT MONO (2185 2735);
FORCEPROP 0 LASTPIN (2175 3425) $PN EC54
J 0
(2185 3435);
DISPLAY 0.680851 (2185 3435);
PAINT MONO (2185 3435);
FORCEPROP 0 LASTPIN (2175 3525) $PN EC60
J 0
(2185 3535);
DISPLAY 0.680851 (2185 3535);
PAINT MONO (2185 3535);
FORCEPROP 0 LASTPIN (2175 3575) $PN EC62
J 0
(2185 3585);
DISPLAY 0.680851 (2185 3585);
PAINT MONO (2185 3585);
FORCEPROP 0 LASTPIN (2175 3675) $PN EC68
J 0
(2185 3685);
DISPLAY 0.680851 (2185 3685);
PAINT MONO (2185 3685);
FORCEPROP 0 LASTPIN (-225 75) $PN ED12
J 2
(-235 85);
DISPLAY 0.680851 (-235 85);
PAINT MONO (-235 85);
FORCEPROP 0 LASTPIN (-225 175) $PN ED18
J 2
(-235 185);
DISPLAY 0.680851 (-235 185);
PAINT MONO (-235 185);
FORCEPROP 0 LASTPIN (-225 375) $PN ED42
J 2
(-235 385);
DISPLAY 0.680851 (-235 385);
PAINT MONO (-235 385);
FORCEPROP 0 LASTPIN (-225 475) $PN ED55
J 2
(-235 485);
DISPLAY 0.680851 (-235 485);
PAINT MONO (-235 485);
FORCEPROP 0 LASTPIN (-225 525) $PN ED61
J 2
(-235 535);
DISPLAY 0.680851 (-235 535);
PAINT MONO (-235 535);
FORCEPROP 0 LASTPIN (-225 575) $PN ED67
J 2
(-235 585);
DISPLAY 0.680851 (-235 585);
PAINT MONO (-235 585);
FORCEPROP 0 LASTPIN (-225 625) $PN ED73
J 2
(-235 635);
DISPLAY 0.680851 (-235 635);
PAINT MONO (-235 635);
FORCEPROP 0 LASTPIN (-225 675) $PN EE17
J 2
(-235 685);
DISPLAY 0.680851 (-235 685);
PAINT MONO (-235 685);
FORCEPROP 0 LASTPIN (-225 725) $PN EE39
J 2
(-235 735);
DISPLAY 0.680851 (-235 735);
PAINT MONO (-235 735);
FORCEPROP 0 LASTPIN (-225 775) $PN EE52
J 2
(-235 785);
DISPLAY 0.680851 (-235 785);
PAINT MONO (-235 785);
FORCEPROP 0 LASTPIN (2175 -175) $PN DW66
J 0
(2185 -165);
DISPLAY 0.680851 (2185 -165);
PAINT MONO (2185 -165);
FORCEPROP 0 LASTPIN (2175 -125) $PN DW68
J 0
(2185 -115);
DISPLAY 0.680851 (2185 -115);
PAINT MONO (2185 -115);
FORCEPROP 0 LASTPIN (2175 -75) $PN DW70
J 0
(2185 -65);
DISPLAY 0.680851 (2185 -65);
PAINT MONO (2185 -65);
FORCEPROP 0 LASTPIN (2175 -25) $PN DW72
J 0
(2185 -15);
DISPLAY 0.680851 (2185 -15);
PAINT MONO (2185 -15);
FORCEPROP 0 LASTPIN (2175 25) $PN DW74
J 0
(2185 35);
DISPLAY 0.680851 (2185 35);
PAINT MONO (2185 35);
FORCEPROP 0 LASTPIN (2175 75) $PN DW76
J 0
(2185 85);
DISPLAY 0.680851 (2185 85);
PAINT MONO (2185 85);
FORCEPROP 0 LASTPIN (2175 125) $PN DW80
J 0
(2185 135);
DISPLAY 0.680851 (2185 135);
PAINT MONO (2185 135);
FORCEPROP 0 LASTPIN (2175 175) $PN DW82
J 0
(2185 185);
DISPLAY 0.680851 (2185 185);
PAINT MONO (2185 185);
FORCEPROP 0 LASTPIN (-225 2025) $PN EF51
J 2
(-235 2035);
DISPLAY 0.680851 (-235 2035);
PAINT MONO (-235 2035);
FORCEPROP 0 LASTPIN (2175 225) $PN DW84
J 0
(2185 235);
DISPLAY 0.680851 (2185 235);
PAINT MONO (2185 235);
FORCEPROP 0 LASTPIN (2175 275) $PN DW88
J 0
(2185 285);
DISPLAY 0.680851 (2185 285);
PAINT MONO (2185 285);
FORCEPROP 0 LASTPIN (2175 575) $PN DY77
J 0
(2185 585);
DISPLAY 0.680851 (2185 585);
PAINT MONO (2185 585);
FORCEPROP 0 LASTPIN (2175 375) $PN DY8
J 0
(2185 385);
DISPLAY 0.680851 (2185 385);
PAINT MONO (2185 385);
FORCEPROP 0 LASTPIN (2175 625) $PN EA21
J 0
(2185 635);
DISPLAY 0.680851 (2185 635);
PAINT MONO (2185 635);
FORCEPROP 0 LASTPIN (2175 675) $PN EA27
J 0
(2185 685);
DISPLAY 0.680851 (2185 685);
PAINT MONO (2185 685);
FORCEPROP 0 LASTPIN (-225 2575) $PN EF73
J 2
(-235 2585);
DISPLAY 0.680851 (-235 2585);
PAINT MONO (-235 2585);
FORCEPROP 0 LASTPIN (-225 2625) $PN EF75
J 2
(-235 2635);
DISPLAY 0.680851 (-235 2635);
PAINT MONO (-235 2635);
FORCEPROP 0 LASTPIN (2175 725) $PN EA33
J 0
(2185 735);
DISPLAY 0.680851 (2185 735);
PAINT MONO (2185 735);
FORCEPROP 0 LASTPIN (2175 1025) $PN EA70
J 0
(2185 1035);
DISPLAY 0.680851 (2185 1035);
PAINT MONO (2185 1035);
FORCEPROP 0 LASTPIN (2175 1075) $PN EA76
J 0
(2185 1085);
DISPLAY 0.680851 (2185 1085);
PAINT MONO (2185 1085);
FORCEPROP 0 LASTPIN (2175 1125) $PN EA78
J 0
(2185 1135);
DISPLAY 0.680851 (2185 1135);
PAINT MONO (2185 1135);
FORCEPROP 0 LASTPIN (2175 1175) $PN EA80
J 0
(2185 1185);
DISPLAY 0.680851 (2185 1185);
PAINT MONO (2185 1185);
FORCEPROP 0 LASTPIN (-225 2825) $PN EF89
J 2
(-235 2835);
DISPLAY 0.680851 (-235 2835);
PAINT MONO (-235 2835);
FORCEPROP 0 LASTPIN (-225 3025) $PN EG13
J 2
(-235 3035);
DISPLAY 0.680851 (-235 3035);
PAINT MONO (-235 3035);
FORCEPROP 0 LASTPIN (2175 1225) $PN EA84
J 0
(2185 1235);
DISPLAY 0.680851 (2185 1235);
PAINT MONO (2185 1235);
FORCEPROP 0 LASTPIN (2175 1275) $PN EA88
J 0
(2185 1285);
DISPLAY 0.680851 (2185 1285);
PAINT MONO (2185 1285);
FORCEPROP 0 LASTPIN (2175 1425) $PN EB12
J 0
(2185 1435);
DISPLAY 0.680851 (2185 1435);
PAINT MONO (2185 1435);
FORCEPROP 0 LASTPIN (2175 1575) $PN EB22
J 0
(2185 1585);
DISPLAY 0.680851 (2185 1585);
PAINT MONO (2185 1585);
FORCEPROP 0 LASTPIN (2175 1675) $PN EB28
J 0
(2185 1685);
DISPLAY 0.680851 (2185 1685);
PAINT MONO (2185 1685);
FORCEPROP 0 LASTPIN (-225 2875) $PN EG5
J 2
(-235 2885);
DISPLAY 0.680851 (-235 2885);
PAINT MONO (-235 2885);
FORCEPROP 0 LASTPIN (-225 3125) $PN EG52
J 2
(-235 3135);
DISPLAY 0.680851 (-235 3135);
PAINT MONO (-235 3135);
FORCEPROP 0 LASTPIN (2175 1725) $PN EB32
J 0
(2185 1735);
DISPLAY 0.680851 (2185 1735);
PAINT MONO (2185 1735);
FORCEPROP 0 LASTPIN (2175 1825) $PN EB38
J 0
(2185 1835);
DISPLAY 0.680851 (2185 1835);
PAINT MONO (2185 1835);
FORCEPROP 0 LASTPIN (-225 2925) $PN EG7
J 2
(-235 2935);
DISPLAY 0.680851 (-235 2935);
PAINT MONO (-235 2935);
FORCEPROP 0 LASTPIN (2175 1875) $PN EB40
J 0
(2185 1885);
DISPLAY 0.680851 (2185 1885);
PAINT MONO (2185 1885);
FORCEPROP 0 LASTPIN (2175 1975) $PN EB47
J 0
(2185 1985);
DISPLAY 0.680851 (2185 1985);
PAINT MONO (2185 1985);
FORCEPROP 0 LASTPIN (2175 2125) $PN EB57
J 0
(2185 2135);
DISPLAY 0.680851 (2185 2135);
PAINT MONO (2185 2135);
FORCEPROP 0 LASTPIN (2175 2275) $PN EB65
J 0
(2185 2285);
DISPLAY 0.680851 (2185 2285);
PAINT MONO (2185 2285);
FORCEPROP 0 LASTPIN (2175 2325) $PN EB69
J 0
(2185 2335);
DISPLAY 0.680851 (2185 2335);
PAINT MONO (2185 2335);
FORCEPROP 0 LASTPIN (2175 2375) $PN EB71
J 0
(2185 2385);
DISPLAY 0.680851 (2185 2385);
PAINT MONO (2185 2385);
FORCEPROP 0 LASTPIN (2175 2425) $PN EB75
J 0
(2185 2435);
DISPLAY 0.680851 (2185 2435);
PAINT MONO (2185 2435);
FORCEPROP 0 LASTPIN (-225 3525) $PN EH12
J 2
(-235 3535);
DISPLAY 0.680851 (-235 3535);
PAINT MONO (-235 3535);
FORCEPROP 0 LASTPIN (-225 3575) $PN EH14
J 2
(-235 3585);
DISPLAY 0.680851 (-235 3585);
PAINT MONO (-235 3585);
FORCEPROP 0 LASTPIN (2175 2475) $PN EB79
J 0
(2185 2485);
DISPLAY 0.680851 (2185 2485);
PAINT MONO (2185 2485);
FORCEPROP 0 LASTPIN (-225 3675) $PN EH18
J 2
(-235 3685);
DISPLAY 0.680851 (-235 3685);
PAINT MONO (-235 3685);
FORCEPROP 0 LASTPIN (2175 1375) $PN EB8
J 0
(2185 1385);
DISPLAY 0.680851 (2185 1385);
PAINT MONO (2185 1385);
FORCEPROP 0 LASTPIN (2175 2525) $PN EB83
J 0
(2185 2535);
DISPLAY 0.680851 (2185 2535);
PAINT MONO (2185 2535);
FORCEPROP 0 LASTPIN (2175 2575) $PN EB87
J 0
(2185 2585);
DISPLAY 0.680851 (2185 2585);
PAINT MONO (2185 2585);
FORCEPROP 0 LASTPIN (2175 2675) $PN EC1
J 0
(2185 2685);
DISPLAY 0.680851 (2185 2685);
PAINT MONO (2185 2685);
FORCEPROP 0 LASTPIN (2175 2825) $PN EC13
J 0
(2185 2835);
DISPLAY 0.680851 (2185 2835);
PAINT MONO (2185 2835);
FORCEPROP 0 LASTPIN (2175 2875) $PN EC19
J 0
(2185 2885);
DISPLAY 0.680851 (2185 2885);
PAINT MONO (2185 2885);
FORCEPROP 0 LASTPIN (2175 2925) $PN EC23
J 0
(2185 2935);
DISPLAY 0.680851 (2185 2935);
PAINT MONO (2185 2935);
FORCEPROP 0 LASTPIN (2175 3025) $PN EC29
J 0
(2185 3035);
DISPLAY 0.680851 (2185 3035);
PAINT MONO (2185 3035);
FORCEPROP 0 LASTPIN (2175 3075) $PN EC31
J 0
(2185 3085);
DISPLAY 0.680851 (2185 3085);
PAINT MONO (2185 3085);
FORCEPROP 0 LASTPIN (2175 3175) $PN EC37
J 0
(2185 3185);
DISPLAY 0.680851 (2185 3185);
PAINT MONO (2185 3185);
FORCEPROP 0 LASTPIN (-225 3475) $PN EH6
J 2
(-235 3485);
DISPLAY 0.680851 (-235 3485);
PAINT MONO (-235 3485);
FORCEPROP 0 LASTPIN (2175 3225) $PN EC41
J 0
(2185 3235);
DISPLAY 0.680851 (2185 3235);
PAINT MONO (2185 3235);
FORCEPROP 0 LASTPIN (2175 3275) $PN EC43
J 0
(2185 3285);
DISPLAY 0.680851 (2185 3285);
PAINT MONO (2185 3285);
FORCEPROP 0 LASTPIN (2175 3325) $PN EC48
J 0
(2185 3335);
DISPLAY 0.680851 (2185 3335);
PAINT MONO (2185 3335);
FORCEPROP 0 LASTPIN (2175 3375) $PN EC50
J 0
(2185 3385);
DISPLAY 0.680851 (2185 3385);
PAINT MONO (2185 3385);
FORCEPROP 0 LASTPIN (2175 3475) $PN EC56
J 0
(2185 3485);
DISPLAY 0.680851 (2185 3485);
PAINT MONO (2185 3485);
FORCEPROP 0 LASTPIN (2175 3625) $PN EC66
J 0
(2185 3635);
DISPLAY 0.680851 (2185 3635);
PAINT MONO (2185 3635);
FORCEPROP 0 LASTPIN (2175 3725) $PN EC72
J 0
(2185 3735);
DISPLAY 0.680851 (2185 3735);
PAINT MONO (2185 3735);
FORCEPROP 0 LASTPIN (2175 3775) $PN EC74
J 0
(2185 3785);
DISPLAY 0.680851 (2185 3785);
PAINT MONO (2185 3785);
FORCEPROP 0 LASTPIN (-225 -175) $PN EC82
J 2
(-235 -165);
DISPLAY 0.680851 (-235 -165);
PAINT MONO (-235 -165);
FORCEPROP 0 LASTPIN (-225 -125) $PN EC84
J 2
(-235 -115);
DISPLAY 0.680851 (-235 -115);
PAINT MONO (-235 -115);
FORCEPROP 0 LASTPIN (-225 -75) $PN EC88
J 2
(-235 -65);
DISPLAY 0.680851 (-235 -65);
PAINT MONO (-235 -65);
FORCEPROP 0 LASTPIN (2175 2775) $PN EC9
J 0
(2185 2785);
DISPLAY 0.680851 (2185 2785);
PAINT MONO (2185 2785);
FORCEPROP 0 LASTPIN (-225 125) $PN ED16
J 2
(-235 135);
DISPLAY 0.680851 (-235 135);
PAINT MONO (-235 135);
FORCEPROP 0 LASTPIN (-225 225) $PN ED24
J 2
(-235 235);
DISPLAY 0.680851 (-235 235);
PAINT MONO (-235 235);
FORCEPROP 0 LASTPIN (-225 275) $PN ED30
J 2
(-235 285);
DISPLAY 0.680851 (-235 285);
PAINT MONO (-235 285);
FORCEPROP 0 LASTPIN (-225 325) $PN ED36
J 2
(-235 335);
DISPLAY 0.680851 (-235 335);
PAINT MONO (-235 335);
FORCEPROP 0 LASTPIN (-225 -25) $PN ED4
J 2
(-235 -15);
DISPLAY 0.680851 (-235 -15);
PAINT MONO (-235 -15);
FORCEPROP 0 LASTPIN (-225 425) $PN ED49
J 2
(-235 435);
DISPLAY 0.680851 (-235 435);
PAINT MONO (-235 435);
FORCEPROP 0 LASTPIN (-225 25) $PN ED8
J 2
(-235 35);
DISPLAY 0.680851 (-235 35);
PAINT MONO (-235 35);
FORCEPROP 0 LASTPIN (-225 825) $PN EE78
J 2
(-235 835);
DISPLAY 0.680851 (-235 835);
PAINT MONO (-235 835);
FORCEPROP 0 LASTPIN (-225 875) $PN EE80
J 2
(-235 885);
DISPLAY 0.680851 (-235 885);
PAINT MONO (-235 885);
FORCEPROP 0 LASTPIN (-225 925) $PN EE88
J 2
(-235 935);
DISPLAY 0.680851 (-235 935);
PAINT MONO (-235 935);
FORCEPROP 0 LASTPIN (-225 1125) $PN EF12
J 2
(-235 1135);
DISPLAY 0.680851 (-235 1135);
PAINT MONO (-235 1135);
FORCEPROP 0 LASTPIN (-225 1175) $PN EF16
J 2
(-235 1185);
DISPLAY 0.680851 (-235 1185);
PAINT MONO (-235 1185);
FORCEPROP 0 LASTPIN (-225 1225) $PN EF18
J 2
(-235 1235);
DISPLAY 0.680851 (-235 1235);
PAINT MONO (-235 1235);
FORCEPROP 0 LASTPIN (-225 975) $PN EF2
J 2
(-235 985);
DISPLAY 0.680851 (-235 985);
PAINT MONO (-235 985);
FORCEPROP 0 LASTPIN (-225 1275) $PN EF20
J 2
(-235 1285);
DISPLAY 0.680851 (-235 1285);
PAINT MONO (-235 1285);
FORCEPROP 0 LASTPIN (-225 1325) $PN EF22
J 2
(-235 1335);
DISPLAY 0.680851 (-235 1335);
PAINT MONO (-235 1335);
FORCEPROP 0 LASTPIN (-225 1375) $PN EF24
J 2
(-235 1385);
DISPLAY 0.680851 (-235 1385);
PAINT MONO (-235 1385);
FORCEPROP 0 LASTPIN (-225 1425) $PN EF26
J 2
(-235 1435);
DISPLAY 0.680851 (-235 1435);
PAINT MONO (-235 1435);
FORCEPROP 0 LASTPIN (-225 1475) $PN EF28
J 2
(-235 1485);
DISPLAY 0.680851 (-235 1485);
PAINT MONO (-235 1485);
FORCEPROP 0 LASTPIN (-225 1525) $PN EF30
J 2
(-235 1535);
DISPLAY 0.680851 (-235 1535);
PAINT MONO (-235 1535);
FORCEPROP 0 LASTPIN (-225 1575) $PN EF32
J 2
(-235 1585);
DISPLAY 0.680851 (-235 1585);
PAINT MONO (-235 1585);
FORCEPROP 0 LASTPIN (-225 1625) $PN EF34
J 2
(-235 1635);
DISPLAY 0.680851 (-235 1635);
PAINT MONO (-235 1635);
FORCEPROP 0 LASTPIN (-225 1675) $PN EF36
J 2
(-235 1685);
DISPLAY 0.680851 (-235 1685);
PAINT MONO (-235 1685);
FORCEPROP 0 LASTPIN (-225 1725) $PN EF38
J 2
(-235 1735);
DISPLAY 0.680851 (-235 1735);
PAINT MONO (-235 1735);
FORCEPROP 0 LASTPIN (-225 1025) $PN EF4
J 2
(-235 1035);
DISPLAY 0.680851 (-235 1035);
PAINT MONO (-235 1035);
FORCEPROP 0 LASTPIN (-225 1775) $PN EF40
J 2
(-235 1785);
DISPLAY 0.680851 (-235 1785);
PAINT MONO (-235 1785);
FORCEPROP 0 LASTPIN (-225 1825) $PN EF42
J 2
(-235 1835);
DISPLAY 0.680851 (-235 1835);
PAINT MONO (-235 1835);
FORCEPROP 0 LASTPIN (-225 1875) $PN EF44
J 2
(-235 1885);
DISPLAY 0.680851 (-235 1885);
PAINT MONO (-235 1885);
FORCEPROP 0 LASTPIN (-225 1925) $PN EF47
J 2
(-235 1935);
DISPLAY 0.680851 (-235 1935);
PAINT MONO (-235 1935);
FORCEPROP 0 LASTPIN (-225 1975) $PN EF49
J 2
(-235 1985);
DISPLAY 0.680851 (-235 1985);
PAINT MONO (-235 1985);
FORCEPROP 0 LASTPIN (-225 2075) $PN EF53
J 2
(-235 2085);
DISPLAY 0.680851 (-235 2085);
PAINT MONO (-235 2085);
FORCEPROP 0 LASTPIN (-225 2125) $PN EF55
J 2
(-235 2135);
DISPLAY 0.680851 (-235 2135);
PAINT MONO (-235 2135);
FORCEPROP 0 LASTPIN (-225 2175) $PN EF57
J 2
(-235 2185);
DISPLAY 0.680851 (-235 2185);
PAINT MONO (-235 2185);
FORCEPROP 0 LASTPIN (-225 2225) $PN EF59
J 2
(-235 2235);
DISPLAY 0.680851 (-235 2235);
PAINT MONO (-235 2235);
FORCEPROP 0 LASTPIN (-225 2275) $PN EF61
J 2
(-235 2285);
DISPLAY 0.680851 (-235 2285);
PAINT MONO (-235 2285);
FORCEPROP 0 LASTPIN (-225 2325) $PN EF63
J 2
(-235 2335);
DISPLAY 0.680851 (-235 2335);
PAINT MONO (-235 2335);
FORCEPROP 0 LASTPIN (-225 2375) $PN EF65
J 2
(-235 2385);
DISPLAY 0.680851 (-235 2385);
PAINT MONO (-235 2385);
FORCEPROP 0 LASTPIN (-225 2425) $PN EF67
J 2
(-235 2435);
DISPLAY 0.680851 (-235 2435);
PAINT MONO (-235 2435);
FORCEPROP 0 LASTPIN (-225 2475) $PN EF69
J 2
(-235 2485);
DISPLAY 0.680851 (-235 2485);
PAINT MONO (-235 2485);
FORCEPROP 0 LASTPIN (-225 2525) $PN EF71
J 2
(-235 2535);
DISPLAY 0.680851 (-235 2535);
PAINT MONO (-235 2535);
FORCEPROP 0 LASTPIN (-225 2675) $PN EF77
J 2
(-235 2685);
DISPLAY 0.680851 (-235 2685);
PAINT MONO (-235 2685);
FORCEPROP 0 LASTPIN (-225 1075) $PN EF8
J 2
(-235 1085);
DISPLAY 0.680851 (-235 1085);
PAINT MONO (-235 1085);
FORCEPROP 0 LASTPIN (-225 2725) $PN EF85
J 2
(-235 2735);
DISPLAY 0.680851 (-235 2735);
PAINT MONO (-235 2735);
FORCEPROP 0 LASTPIN (-225 2775) $PN EF87
J 2
(-235 2785);
DISPLAY 0.680851 (-235 2785);
PAINT MONO (-235 2785);
FORCEPROP 0 LASTPIN (-225 3075) $PN EG39
J 2
(-235 3085);
DISPLAY 0.680851 (-235 3085);
PAINT MONO (-235 3085);
FORCEPROP 0 LASTPIN (-225 3175) $PN EG82
J 2
(-235 3185);
DISPLAY 0.680851 (-235 3185);
PAINT MONO (-235 3185);
FORCEPROP 0 LASTPIN (-225 3225) $PN EG84
J 2
(-235 3235);
DISPLAY 0.680851 (-235 3235);
PAINT MONO (-235 3235);
FORCEPROP 0 LASTPIN (-225 3275) $PN EG86
J 2
(-235 3285);
DISPLAY 0.680851 (-235 3285);
PAINT MONO (-235 3285);
FORCEPROP 0 LASTPIN (-225 3325) $PN EG88
J 2
(-235 3335);
DISPLAY 0.680851 (-235 3335);
PAINT MONO (-235 3335);
FORCEPROP 0 LASTPIN (-225 2975) $PN EG9
J 2
(-235 2985);
DISPLAY 0.680851 (-235 2985);
PAINT MONO (-235 2985);
FORCEPROP 0 LASTPIN (-225 3375) $PN EG90
J 2
(-235 3385);
DISPLAY 0.680851 (-235 3385);
PAINT MONO (-235 3385);
FORCEPROP 0 LASTPIN (-225 3625) $PN EH16
J 2
(-235 3635);
DISPLAY 0.680851 (-235 3635);
PAINT MONO (-235 3635);
FORCEPROP 0 LASTPIN (-225 3725) $PN EH24
J 2
(-235 3735);
DISPLAY 0.680851 (-235 3735);
PAINT MONO (-235 3735);
FORCEPROP 0 LASTPIN (-225 3775) $PN EH30
J 2
(-235 3785);
DISPLAY 0.680851 (-235 3785);
PAINT MONO (-235 3785);
FORCEPROP 0 LASTPIN (-225 3425) $PN EH4
J 2
(-235 3435);
DISPLAY 0.680851 (-235 3435);
PAINT MONO (-235 3435);
FORCEPROP 2 LAST CDS_LIB pure_quanta
J 0
(975 1800);
DISPLAY INVISIBLE (975 1800);
FORCEPROP 1 LAST NEEDS_NO_SIZE TRUE
J 0
(975 1800);
DISPLAY 0.723404 (975 1800);
PAINT GREEN (975 1800);
DISPLAY INVISIBLE (975 1800);
FORCEPROP 1 LAST CDS_LMAN_SYM_OUTLINE -1050,2150,1050,-2100
J 0
(975 1800);
DISPLAY 0.468085 (975 1800);
PAINT GREEN (975 1800);
DISPLAY INVISIBLE (975 1800);
FORCEPROP 0 LAST CDS_LOCATION U1
J 0
(-75 4275);
DISPLAY 1.021277 (-75 4275);
DISPLAY INVISIBLE (-75 4275);
FORCEPROP 0 LAST $SEC 32
J 0
(-75 4275);
DISPLAY 0.680851 (-75 4275);
PAINT MONO (-75 4275);
DISPLAY INVISIBLE (-75 4275);
FORCEPROP 2 LAST CDS_SEC 32
J 0
(-75 4275);
DISPLAY 1.021277 (-75 4275);
DISPLAY INVISIBLE (-75 4275);
FORCEPROP 1 LAST PATH I5
J 0
(975 1800);
DISPLAY 0.723404 (975 1800);
PAINT GREEN (975 1800);
DISPLAY INVISIBLE (975 1800);
FORCEADD UNIVERSAL_GND..1
(2425 -725);
FORCEPROP 3 LASTPIN (2425 -675) SIG_NAME GND\g
J 0
(2435 -665);
DISPLAY 0.659574 (2435 -665);
PAINT MONO (2435 -665);
DISPLAY INVISIBLE (2435 -665);
FORCEPROP 2 LAST CDS_LIB logical_power
J 0
(2425 -725);
PAINT MONO (2425 -725);
DISPLAY INVISIBLE (2425 -725);
FORCEPROP 1 LAST HDL_POWER GND
J 1
(2450 -800);
DISPLAY 0.872340 (2450 -800);
PAINT GREEN (2450 -800);
DISPLAY INVISIBLE (2450 -800);
FORCEPROP 1 LAST PATH I6
J 0
(2500 -725);
DISPLAY 0.872340 (2500 -725);
PAINT AQUA (2500 -725);
DISPLAY INVISIBLE (2500 -725);
FORCEADD UNIVERSAL_GND..1
(2550 -725);
FORCEPROP 3 LASTPIN (2550 -675) SIG_NAME GND\g
J 0
(2560 -665);
DISPLAY 0.659574 (2560 -665);
PAINT MONO (2560 -665);
DISPLAY INVISIBLE (2560 -665);
FORCEPROP 2 LAST CDS_LIB logical_power
J 0
(2550 -725);
PAINT MONO (2550 -725);
DISPLAY INVISIBLE (2550 -725);
FORCEPROP 1 LAST HDL_POWER GND
J 1
(2575 -800);
DISPLAY 0.872340 (2575 -800);
PAINT GREEN (2575 -800);
DISPLAY INVISIBLE (2575 -800);
FORCEPROP 1 LAST PATH I7
J 0
(2625 -725);
DISPLAY 0.872340 (2625 -725);
PAINT AQUA (2625 -725);
DISPLAY INVISIBLE (2625 -725);
FORCEADD SOCKET4677_AZIF0045P001C01CS..33
(4000 1800);
FORCEPROP 1 LAST PART_NUMBER DGA^7000023
J 0
(2950 4050);
DISPLAY 0.723404 (2950 4050);
PAINT GREEN (2950 4050);
DISPLAY INVISIBLE (2950 4050);
FORCEPROP 2 LAST PART_TYPE SMLF
J 0
(2950 4225);
DISPLAY 1.021277 (2950 4225);
FORCEPROP 1 LAST MATERIAL IO
J 0
(2950 3975);
DISPLAY 0.723404 (2950 3975);
PAINT GREEN (2950 3975);
FORCEPROP 2 LAST VALUE SOCKET4677_AZIF0045-P001C01CS
J 0
(2950 4175);
DISPLAY 1.021277 (2950 4175);
FORCEPROP 1 LAST $LOCATION U1
J 0
(2950 4125);
DISPLAY 0.723404 (2950 4125);
PAINT GREEN (2950 4125);
FORCEPROP 0 LASTPIN (5200 825) $PN DM51
J 0
(5210 835);
DISPLAY 0.680851 (5210 835);
PAINT MONO (5210 835);
FORCEPROP 0 LASTPIN (5200 1375) $PN DM73
J 0
(5210 1385);
DISPLAY 0.680851 (5210 1385);
PAINT MONO (5210 1385);
FORCEPROP 0 LASTPIN (5200 1575) $PN DN17
J 0
(5210 1585);
DISPLAY 0.680851 (5210 1585);
PAINT MONO (5210 1585);
FORCEPROP 0 LASTPIN (5200 1625) $PN DN39
J 0
(5210 1635);
DISPLAY 0.680851 (5210 1635);
PAINT MONO (5210 1635);
FORCEPROP 0 LASTPIN (5200 1675) $PN DN52
J 0
(5210 1685);
DISPLAY 0.680851 (5210 1685);
PAINT MONO (5210 1685);
FORCEPROP 0 LASTPIN (5200 1975) $PN DP12
J 0
(5210 1985);
DISPLAY 0.680851 (5210 1985);
PAINT MONO (5210 1985);
FORCEPROP 0 LASTPIN (5200 2075) $PN DP18
J 0
(5210 2085);
DISPLAY 0.680851 (5210 2085);
PAINT MONO (5210 2085);
FORCEPROP 0 LASTPIN (5200 2125) $PN DP24
J 0
(5210 2135);
DISPLAY 0.680851 (5210 2135);
PAINT MONO (5210 2135);
FORCEPROP 0 LASTPIN (5200 2275) $PN DP42
J 0
(5210 2285);
DISPLAY 0.680851 (5210 2285);
PAINT MONO (5210 2285);
FORCEPROP 0 LASTPIN (5200 2375) $PN DP55
J 0
(5210 2385);
DISPLAY 0.680851 (5210 2385);
PAINT MONO (5210 2385);
FORCEPROP 0 LASTPIN (5200 2425) $PN DP61
J 0
(5210 2435);
DISPLAY 0.680851 (5210 2435);
PAINT MONO (5210 2435);
FORCEPROP 0 LASTPIN (5200 2475) $PN DP67
J 0
(5210 2485);
DISPLAY 0.680851 (5210 2485);
PAINT MONO (5210 2485);
FORCEPROP 0 LASTPIN (5200 2675) $PN DP91
J 0
(5210 2685);
DISPLAY 0.680851 (5210 2685);
PAINT MONO (5210 2685);
FORCEPROP 0 LASTPIN (5200 3025) $PN DR25
J 0
(5210 3035);
DISPLAY 0.680851 (5210 3035);
PAINT MONO (5210 3035);
FORCEPROP 0 LASTPIN (5200 3175) $PN DR35
J 0
(5210 3185);
DISPLAY 0.680851 (5210 3185);
PAINT MONO (5210 3185);
FORCEPROP 0 LASTPIN (5200 2775) $PN DR5
J 0
(5210 2785);
DISPLAY 0.680851 (5210 2785);
PAINT MONO (5210 2785);
FORCEPROP 0 LASTPIN (5200 3475) $PN DR54
J 0
(5210 3485);
DISPLAY 0.680851 (5210 3485);
PAINT MONO (5210 3485);
FORCEPROP 0 LASTPIN (5200 3575) $PN DR60
J 0
(5210 3585);
DISPLAY 0.680851 (5210 3585);
PAINT MONO (5210 3585);
FORCEPROP 0 LASTPIN (5200 3625) $PN DR62
J 0
(5210 3635);
DISPLAY 0.680851 (5210 3635);
PAINT MONO (5210 3635);
FORCEPROP 0 LASTPIN (5200 3725) $PN DR68
J 0
(5210 3735);
DISPLAY 0.680851 (5210 3735);
PAINT MONO (5210 3735);
FORCEPROP 0 LASTPIN (5200 3775) $PN DR72
J 0
(5210 3785);
DISPLAY 0.680851 (5210 3785);
PAINT MONO (5210 3785);
FORCEPROP 0 LASTPIN (2800 175) $PN DT16
J 2
(2790 185);
DISPLAY 0.680851 (2790 185);
PAINT MONO (2790 185);
FORCEPROP 0 LASTPIN (2800 225) $PN DT20
J 2
(2790 235);
DISPLAY 0.680851 (2790 235);
PAINT MONO (2790 235);
FORCEPROP 0 LASTPIN (2800 325) $PN DT26
J 2
(2790 335);
DISPLAY 0.680851 (2790 335);
PAINT MONO (2790 335);
FORCEPROP 0 LASTPIN (2800 25) $PN DT4
J 2
(2790 35);
DISPLAY 0.680851 (2790 35);
PAINT MONO (2790 35);
FORCEPROP 0 LASTPIN (2800 625) $PN DT44
J 2
(2790 635);
DISPLAY 0.680851 (2790 635);
PAINT MONO (2790 635);
FORCEPROP 0 LASTPIN (2800 725) $PN DT51
J 2
(2790 735);
DISPLAY 0.680851 (2790 735);
PAINT MONO (2790 735);
FORCEPROP 0 LASTPIN (2800 775) $PN DT53
J 2
(2790 785);
DISPLAY 0.680851 (2790 785);
PAINT MONO (2790 785);
FORCEPROP 0 LASTPIN (2800 875) $PN DT59
J 2
(2790 885);
DISPLAY 0.680851 (2790 885);
PAINT MONO (2790 885);
FORCEPROP 0 LASTPIN (2800 925) $PN DT63
J 2
(2790 935);
DISPLAY 0.680851 (2790 935);
PAINT MONO (2790 935);
FORCEPROP 0 LASTPIN (2800 1175) $PN DT83
J 2
(2790 1185);
DISPLAY 0.680851 (2790 1185);
PAINT MONO (2790 1185);
FORCEPROP 0 LASTPIN (2800 1375) $PN DU39
J 2
(2790 1385);
DISPLAY 0.680851 (2790 1385);
PAINT MONO (2790 1385);
FORCEPROP 0 LASTPIN (2800 1425) $PN DU45
J 2
(2790 1435);
DISPLAY 0.680851 (2790 1435);
PAINT MONO (2790 1435);
FORCEPROP 0 LASTPIN (2800 1475) $PN DU52
J 2
(2790 1485);
DISPLAY 0.680851 (2790 1485);
PAINT MONO (2790 1485);
FORCEPROP 0 LASTPIN (2800 1525) $PN DU58
J 2
(2790 1535);
DISPLAY 0.680851 (2790 1535);
PAINT MONO (2790 1535);
FORCEPROP 0 LASTPIN (2800 1575) $PN DU64
J 2
(2790 1585);
DISPLAY 0.680851 (2790 1585);
PAINT MONO (2790 1585);
FORCEPROP 0 LASTPIN (2800 1625) $PN DU70
J 2
(2790 1635);
DISPLAY 0.680851 (2790 1635);
PAINT MONO (2790 1635);
FORCEPROP 0 LASTPIN (2800 1975) $PN DV12
J 2
(2790 1985);
DISPLAY 0.680851 (2790 1985);
PAINT MONO (2790 1985);
FORCEPROP 0 LASTPIN (2800 2025) $PN DV16
J 2
(2790 2035);
DISPLAY 0.680851 (2790 2035);
PAINT MONO (2790 2035);
FORCEPROP 0 LASTPIN (2800 1875) $PN DV4
J 2
(2790 1885);
DISPLAY 0.680851 (2790 1885);
PAINT MONO (2790 1885);
FORCEPROP 0 LASTPIN (2800 2075) $PN DV42
J 2
(2790 2085);
DISPLAY 0.680851 (2790 2085);
PAINT MONO (2790 2085);
FORCEPROP 0 LASTPIN (2800 2725) $PN DW21
J 2
(2790 2735);
DISPLAY 0.680851 (2790 2735);
PAINT MONO (2790 2735);
FORCEPROP 0 LASTPIN (2800 3675) $PN DW60
J 2
(2790 3685);
DISPLAY 0.680851 (2790 3685);
PAINT MONO (2790 3685);
FORCEPROP 0 LASTPIN (5200 -75) $PN DM12
J 0
(5210 -65);
DISPLAY 0.680851 (5210 -65);
PAINT MONO (5210 -65);
FORCEPROP 0 LASTPIN (5200 -25) $PN DM16
J 0
(5210 -15);
DISPLAY 0.680851 (5210 -15);
PAINT MONO (5210 -15);
FORCEPROP 0 LASTPIN (5200 25) $PN DM18
J 0
(5210 35);
DISPLAY 0.680851 (5210 35);
PAINT MONO (5210 35);
FORCEPROP 0 LASTPIN (5200 75) $PN DM20
J 0
(5210 85);
DISPLAY 0.680851 (5210 85);
PAINT MONO (5210 85);
FORCEPROP 0 LASTPIN (5200 125) $PN DM22
J 0
(5210 135);
DISPLAY 0.680851 (5210 135);
PAINT MONO (5210 135);
FORCEPROP 0 LASTPIN (5200 175) $PN DM24
J 0
(5210 185);
DISPLAY 0.680851 (5210 185);
PAINT MONO (5210 185);
FORCEPROP 0 LASTPIN (5200 225) $PN DM26
J 0
(5210 235);
DISPLAY 0.680851 (5210 235);
PAINT MONO (5210 235);
FORCEPROP 0 LASTPIN (5200 275) $PN DM28
J 0
(5210 285);
DISPLAY 0.680851 (5210 285);
PAINT MONO (5210 285);
FORCEPROP 0 LASTPIN (5200 325) $PN DM30
J 0
(5210 335);
DISPLAY 0.680851 (5210 335);
PAINT MONO (5210 335);
FORCEPROP 0 LASTPIN (5200 375) $PN DM32
J 0
(5210 385);
DISPLAY 0.680851 (5210 385);
PAINT MONO (5210 385);
FORCEPROP 0 LASTPIN (5200 425) $PN DM34
J 0
(5210 435);
DISPLAY 0.680851 (5210 435);
PAINT MONO (5210 435);
FORCEPROP 0 LASTPIN (5200 475) $PN DM36
J 0
(5210 485);
DISPLAY 0.680851 (5210 485);
PAINT MONO (5210 485);
FORCEPROP 0 LASTPIN (5200 525) $PN DM38
J 0
(5210 535);
DISPLAY 0.680851 (5210 535);
PAINT MONO (5210 535);
FORCEPROP 0 LASTPIN (5200 -175) $PN DM4
J 0
(5210 -165);
DISPLAY 0.680851 (5210 -165);
PAINT MONO (5210 -165);
FORCEPROP 0 LASTPIN (5200 575) $PN DM40
J 0
(5210 585);
DISPLAY 0.680851 (5210 585);
PAINT MONO (5210 585);
FORCEPROP 0 LASTPIN (5200 625) $PN DM42
J 0
(5210 635);
DISPLAY 0.680851 (5210 635);
PAINT MONO (5210 635);
FORCEPROP 0 LASTPIN (5200 675) $PN DM44
J 0
(5210 685);
DISPLAY 0.680851 (5210 685);
PAINT MONO (5210 685);
FORCEPROP 0 LASTPIN (5200 725) $PN DM47
J 0
(5210 735);
DISPLAY 0.680851 (5210 735);
PAINT MONO (5210 735);
FORCEPROP 0 LASTPIN (5200 775) $PN DM49
J 0
(5210 785);
DISPLAY 0.680851 (5210 785);
PAINT MONO (5210 785);
FORCEPROP 0 LASTPIN (5200 875) $PN DM53
J 0
(5210 885);
DISPLAY 0.680851 (5210 885);
PAINT MONO (5210 885);
FORCEPROP 0 LASTPIN (5200 925) $PN DM55
J 0
(5210 935);
DISPLAY 0.680851 (5210 935);
PAINT MONO (5210 935);
FORCEPROP 0 LASTPIN (5200 975) $PN DM57
J 0
(5210 985);
DISPLAY 0.680851 (5210 985);
PAINT MONO (5210 985);
FORCEPROP 0 LASTPIN (5200 1025) $PN DM59
J 0
(5210 1035);
DISPLAY 0.680851 (5210 1035);
PAINT MONO (5210 1035);
FORCEPROP 0 LASTPIN (5200 1075) $PN DM61
J 0
(5210 1085);
DISPLAY 0.680851 (5210 1085);
PAINT MONO (5210 1085);
FORCEPROP 0 LASTPIN (5200 1125) $PN DM63
J 0
(5210 1135);
DISPLAY 0.680851 (5210 1135);
PAINT MONO (5210 1135);
FORCEPROP 0 LASTPIN (5200 1175) $PN DM65
J 0
(5210 1185);
DISPLAY 0.680851 (5210 1185);
PAINT MONO (5210 1185);
FORCEPROP 0 LASTPIN (5200 1225) $PN DM67
J 0
(5210 1235);
DISPLAY 0.680851 (5210 1235);
PAINT MONO (5210 1235);
FORCEPROP 0 LASTPIN (5200 1275) $PN DM69
J 0
(5210 1285);
DISPLAY 0.680851 (5210 1285);
PAINT MONO (5210 1285);
FORCEPROP 0 LASTPIN (5200 1325) $PN DM71
J 0
(5210 1335);
DISPLAY 0.680851 (5210 1335);
PAINT MONO (5210 1335);
FORCEPROP 0 LASTPIN (5200 1425) $PN DM75
J 0
(5210 1435);
DISPLAY 0.680851 (5210 1435);
PAINT MONO (5210 1435);
FORCEPROP 0 LASTPIN (5200 1475) $PN DM77
J 0
(5210 1485);
DISPLAY 0.680851 (5210 1485);
PAINT MONO (5210 1485);
FORCEPROP 0 LASTPIN (5200 1525) $PN DM79
J 0
(5210 1535);
DISPLAY 0.680851 (5210 1535);
PAINT MONO (5210 1535);
FORCEPROP 0 LASTPIN (5200 -125) $PN DM8
J 0
(5210 -115);
DISPLAY 0.680851 (5210 -115);
PAINT MONO (5210 -115);
FORCEPROP 0 LASTPIN (5200 1725) $PN DN78
J 0
(5210 1735);
DISPLAY 0.680851 (5210 1735);
PAINT MONO (5210 1735);
FORCEPROP 0 LASTPIN (5200 1775) $PN DN84
J 0
(5210 1785);
DISPLAY 0.680851 (5210 1785);
PAINT MONO (5210 1785);
FORCEPROP 0 LASTPIN (5200 1825) $PN DN88
J 0
(5210 1835);
DISPLAY 0.680851 (5210 1835);
PAINT MONO (5210 1835);
FORCEPROP 0 LASTPIN (5200 2025) $PN DP16
J 0
(5210 2035);
DISPLAY 0.680851 (5210 2035);
PAINT MONO (5210 2035);
FORCEPROP 0 LASTPIN (5200 2175) $PN DP30
J 0
(5210 2185);
DISPLAY 0.680851 (5210 2185);
PAINT MONO (5210 2185);
FORCEPROP 0 LASTPIN (5200 2225) $PN DP36
J 0
(5210 2235);
DISPLAY 0.680851 (5210 2235);
PAINT MONO (5210 2235);
FORCEPROP 0 LASTPIN (5200 1875) $PN DP4
J 0
(5210 1885);
DISPLAY 0.680851 (5210 1885);
PAINT MONO (5210 1885);
FORCEPROP 0 LASTPIN (5200 2325) $PN DP49
J 0
(5210 2335);
DISPLAY 0.680851 (5210 2335);
PAINT MONO (5210 2335);
FORCEPROP 0 LASTPIN (5200 2525) $PN DP73
J 0
(5210 2535);
DISPLAY 0.680851 (5210 2535);
PAINT MONO (5210 2535);
FORCEPROP 0 LASTPIN (5200 1925) $PN DP8
J 0
(5210 1935);
DISPLAY 0.680851 (5210 1935);
PAINT MONO (5210 1935);
FORCEPROP 0 LASTPIN (5200 2575) $PN DP81
J 0
(5210 2585);
DISPLAY 0.680851 (5210 2585);
PAINT MONO (5210 2585);
FORCEPROP 0 LASTPIN (5200 2625) $PN DP87
J 0
(5210 2635);
DISPLAY 0.680851 (5210 2635);
PAINT MONO (5210 2635);
FORCEPROP 0 LASTPIN (5200 2725) $PN DR1
J 0
(5210 2735);
DISPLAY 0.680851 (5210 2735);
PAINT MONO (5210 2735);
FORCEPROP 0 LASTPIN (5200 2875) $PN DR13
J 0
(5210 2885);
DISPLAY 0.680851 (5210 2885);
PAINT MONO (5210 2885);
FORCEPROP 0 LASTPIN (5200 2925) $PN DR19
J 0
(5210 2935);
DISPLAY 0.680851 (5210 2935);
PAINT MONO (5210 2935);
FORCEPROP 0 LASTPIN (5200 2975) $PN DR23
J 0
(5210 2985);
DISPLAY 0.680851 (5210 2985);
PAINT MONO (5210 2985);
FORCEPROP 0 LASTPIN (5200 3075) $PN DR29
J 0
(5210 3085);
DISPLAY 0.680851 (5210 3085);
PAINT MONO (5210 3085);
FORCEPROP 0 LASTPIN (5200 3125) $PN DR31
J 0
(5210 3135);
DISPLAY 0.680851 (5210 3135);
PAINT MONO (5210 3135);
FORCEPROP 0 LASTPIN (5200 3225) $PN DR37
J 0
(5210 3235);
DISPLAY 0.680851 (5210 3235);
PAINT MONO (5210 3235);
FORCEPROP 0 LASTPIN (5200 3275) $PN DR41
J 0
(5210 3285);
DISPLAY 0.680851 (5210 3285);
PAINT MONO (5210 3285);
FORCEPROP 0 LASTPIN (5200 3325) $PN DR43
J 0
(5210 3335);
DISPLAY 0.680851 (5210 3335);
PAINT MONO (5210 3335);
FORCEPROP 0 LASTPIN (5200 3375) $PN DR48
J 0
(5210 3385);
DISPLAY 0.680851 (5210 3385);
PAINT MONO (5210 3385);
FORCEPROP 0 LASTPIN (5200 3425) $PN DR50
J 0
(5210 3435);
DISPLAY 0.680851 (5210 3435);
PAINT MONO (5210 3435);
FORCEPROP 0 LASTPIN (5200 3525) $PN DR56
J 0
(5210 3535);
DISPLAY 0.680851 (5210 3535);
PAINT MONO (5210 3535);
FORCEPROP 0 LASTPIN (5200 3675) $PN DR66
J 0
(5210 3685);
DISPLAY 0.680851 (5210 3685);
PAINT MONO (5210 3685);
FORCEPROP 0 LASTPIN (2800 -175) $PN DR74
J 2
(2790 -165);
DISPLAY 0.680851 (2790 -165);
PAINT MONO (2790 -165);
FORCEPROP 0 LASTPIN (2800 -125) $PN DR78
J 2
(2790 -115);
DISPLAY 0.680851 (2790 -115);
PAINT MONO (2790 -115);
FORCEPROP 0 LASTPIN (2800 -75) $PN DR84
J 2
(2790 -65);
DISPLAY 0.680851 (2790 -65);
PAINT MONO (2790 -65);
FORCEPROP 0 LASTPIN (2800 -25) $PN DR88
J 2
(2790 -15);
DISPLAY 0.680851 (2790 -15);
PAINT MONO (2790 -15);
FORCEPROP 0 LASTPIN (5200 2825) $PN DR9
J 0
(5210 2835);
DISPLAY 0.680851 (5210 2835);
PAINT MONO (5210 2835);
FORCEPROP 0 LASTPIN (2800 125) $PN DT12
J 2
(2790 135);
DISPLAY 0.680851 (2790 135);
PAINT MONO (2790 135);
FORCEPROP 0 LASTPIN (2800 275) $PN DT22
J 2
(2790 285);
DISPLAY 0.680851 (2790 285);
PAINT MONO (2790 285);
FORCEPROP 0 LASTPIN (2800 375) $PN DT28
J 2
(2790 385);
DISPLAY 0.680851 (2790 385);
PAINT MONO (2790 385);
FORCEPROP 0 LASTPIN (2800 425) $PN DT32
J 2
(2790 435);
DISPLAY 0.680851 (2790 435);
PAINT MONO (2790 435);
FORCEPROP 0 LASTPIN (2800 475) $PN DT34
J 2
(2790 485);
DISPLAY 0.680851 (2790 485);
PAINT MONO (2790 485);
FORCEPROP 0 LASTPIN (2800 525) $PN DT38
J 2
(2790 535);
DISPLAY 0.680851 (2790 535);
PAINT MONO (2790 535);
FORCEPROP 0 LASTPIN (2800 575) $PN DT40
J 2
(2790 585);
DISPLAY 0.680851 (2790 585);
PAINT MONO (2790 585);
FORCEPROP 0 LASTPIN (2800 675) $PN DT47
J 2
(2790 685);
DISPLAY 0.680851 (2790 685);
PAINT MONO (2790 685);
FORCEPROP 0 LASTPIN (2800 825) $PN DT57
J 2
(2790 835);
DISPLAY 0.680851 (2790 835);
PAINT MONO (2790 835);
FORCEPROP 0 LASTPIN (2800 975) $PN DT65
J 2
(2790 985);
DISPLAY 0.680851 (2790 985);
PAINT MONO (2790 985);
FORCEPROP 0 LASTPIN (2800 1025) $PN DT69
J 2
(2790 1035);
DISPLAY 0.680851 (2790 1035);
PAINT MONO (2790 1035);
FORCEPROP 0 LASTPIN (2800 1075) $PN DT71
J 2
(2790 1085);
DISPLAY 0.680851 (2790 1085);
PAINT MONO (2790 1085);
FORCEPROP 0 LASTPIN (2800 1125) $PN DT75
J 2
(2790 1135);
DISPLAY 0.680851 (2790 1135);
PAINT MONO (2790 1135);
FORCEPROP 0 LASTPIN (2800 75) $PN DT8
J 2
(2790 85);
DISPLAY 0.680851 (2790 85);
PAINT MONO (2790 85);
FORCEPROP 0 LASTPIN (2800 1225) $PN DU21
J 2
(2790 1235);
DISPLAY 0.680851 (2790 1235);
PAINT MONO (2790 1235);
FORCEPROP 0 LASTPIN (2800 1275) $PN DU27
J 2
(2790 1285);
DISPLAY 0.680851 (2790 1285);
PAINT MONO (2790 1285);
FORCEPROP 0 LASTPIN (2800 1325) $PN DU33
J 2
(2790 1335);
DISPLAY 0.680851 (2790 1335);
PAINT MONO (2790 1335);
FORCEPROP 0 LASTPIN (2800 1675) $PN DU76
J 2
(2790 1685);
DISPLAY 0.680851 (2790 1685);
PAINT MONO (2790 1685);
FORCEPROP 0 LASTPIN (2800 1725) $PN DU78
J 2
(2790 1735);
DISPLAY 0.680851 (2790 1735);
PAINT MONO (2790 1735);
FORCEPROP 0 LASTPIN (2800 1775) $PN DU84
J 2
(2790 1785);
DISPLAY 0.680851 (2790 1785);
PAINT MONO (2790 1785);
FORCEPROP 0 LASTPIN (2800 1825) $PN DU88
J 2
(2790 1835);
DISPLAY 0.680851 (2790 1835);
PAINT MONO (2790 1835);
FORCEPROP 0 LASTPIN (2800 2125) $PN DV77
J 2
(2790 2135);
DISPLAY 0.680851 (2790 2135);
PAINT MONO (2790 2135);
FORCEPROP 0 LASTPIN (2800 2175) $PN DV79
J 2
(2790 2185);
DISPLAY 0.680851 (2790 2185);
PAINT MONO (2790 2185);
FORCEPROP 0 LASTPIN (2800 1925) $PN DV8
J 2
(2790 1935);
DISPLAY 0.680851 (2790 1935);
PAINT MONO (2790 1935);
FORCEPROP 0 LASTPIN (2800 2225) $PN DV81
J 2
(2790 2235);
DISPLAY 0.680851 (2790 2235);
PAINT MONO (2790 2235);
FORCEPROP 0 LASTPIN (2800 2275) $PN DV83
J 2
(2790 2285);
DISPLAY 0.680851 (2790 2285);
PAINT MONO (2790 2285);
FORCEPROP 0 LASTPIN (2800 2325) $PN DV87
J 2
(2790 2335);
DISPLAY 0.680851 (2790 2335);
PAINT MONO (2790 2335);
FORCEPROP 0 LASTPIN (2800 2375) $PN DV91
J 2
(2790 2385);
DISPLAY 0.680851 (2790 2385);
PAINT MONO (2790 2385);
FORCEPROP 0 LASTPIN (2800 2425) $PN DW1
J 2
(2790 2435);
DISPLAY 0.680851 (2790 2435);
PAINT MONO (2790 2435);
FORCEPROP 0 LASTPIN (2800 2575) $PN DW13
J 2
(2790 2585);
DISPLAY 0.680851 (2790 2585);
PAINT MONO (2790 2585);
FORCEPROP 0 LASTPIN (2800 2625) $PN DW17
J 2
(2790 2635);
DISPLAY 0.680851 (2790 2635);
PAINT MONO (2790 2635);
FORCEPROP 0 LASTPIN (2800 2675) $PN DW19
J 2
(2790 2685);
DISPLAY 0.680851 (2790 2685);
PAINT MONO (2790 2685);
FORCEPROP 0 LASTPIN (2800 2775) $PN DW23
J 2
(2790 2785);
DISPLAY 0.680851 (2790 2785);
PAINT MONO (2790 2785);
FORCEPROP 0 LASTPIN (2800 2825) $PN DW25
J 2
(2790 2835);
DISPLAY 0.680851 (2790 2835);
PAINT MONO (2790 2835);
FORCEPROP 0 LASTPIN (2800 2875) $PN DW27
J 2
(2790 2885);
DISPLAY 0.680851 (2790 2885);
PAINT MONO (2790 2885);
FORCEPROP 0 LASTPIN (2800 2925) $PN DW29
J 2
(2790 2935);
DISPLAY 0.680851 (2790 2935);
PAINT MONO (2790 2935);
FORCEPROP 0 LASTPIN (2800 2975) $PN DW31
J 2
(2790 2985);
DISPLAY 0.680851 (2790 2985);
PAINT MONO (2790 2985);
FORCEPROP 0 LASTPIN (2800 3025) $PN DW33
J 2
(2790 3035);
DISPLAY 0.680851 (2790 3035);
PAINT MONO (2790 3035);
FORCEPROP 0 LASTPIN (2800 3075) $PN DW35
J 2
(2790 3085);
DISPLAY 0.680851 (2790 3085);
PAINT MONO (2790 3085);
FORCEPROP 0 LASTPIN (2800 3125) $PN DW37
J 2
(2790 3135);
DISPLAY 0.680851 (2790 3135);
PAINT MONO (2790 3135);
FORCEPROP 0 LASTPIN (2800 3175) $PN DW39
J 2
(2790 3185);
DISPLAY 0.680851 (2790 3185);
PAINT MONO (2790 3185);
FORCEPROP 0 LASTPIN (2800 3225) $PN DW41
J 2
(2790 3235);
DISPLAY 0.680851 (2790 3235);
PAINT MONO (2790 3235);
FORCEPROP 0 LASTPIN (2800 3275) $PN DW43
J 2
(2790 3285);
DISPLAY 0.680851 (2790 3285);
PAINT MONO (2790 3285);
FORCEPROP 0 LASTPIN (2800 3325) $PN DW45
J 2
(2790 3335);
DISPLAY 0.680851 (2790 3335);
PAINT MONO (2790 3335);
FORCEPROP 0 LASTPIN (2800 3375) $PN DW48
J 2
(2790 3385);
DISPLAY 0.680851 (2790 3385);
PAINT MONO (2790 3385);
FORCEPROP 0 LASTPIN (2800 2475) $PN DW5
J 2
(2790 2485);
DISPLAY 0.680851 (2790 2485);
PAINT MONO (2790 2485);
FORCEPROP 0 LASTPIN (2800 3425) $PN DW50
J 2
(2790 3435);
DISPLAY 0.680851 (2790 3435);
PAINT MONO (2790 3435);
FORCEPROP 0 LASTPIN (2800 3475) $PN DW52
J 2
(2790 3485);
DISPLAY 0.680851 (2790 3485);
PAINT MONO (2790 3485);
FORCEPROP 0 LASTPIN (2800 3525) $PN DW54
J 2
(2790 3535);
DISPLAY 0.680851 (2790 3535);
PAINT MONO (2790 3535);
FORCEPROP 0 LASTPIN (2800 3575) $PN DW56
J 2
(2790 3585);
DISPLAY 0.680851 (2790 3585);
PAINT MONO (2790 3585);
FORCEPROP 0 LASTPIN (2800 3625) $PN DW58
J 2
(2790 3635);
DISPLAY 0.680851 (2790 3635);
PAINT MONO (2790 3635);
FORCEPROP 0 LASTPIN (2800 3725) $PN DW62
J 2
(2790 3735);
DISPLAY 0.680851 (2790 3735);
PAINT MONO (2790 3735);
FORCEPROP 0 LASTPIN (2800 3775) $PN DW64
J 2
(2790 3785);
DISPLAY 0.680851 (2790 3785);
PAINT MONO (2790 3785);
FORCEPROP 0 LASTPIN (2800 2525) $PN DW9
J 2
(2790 2535);
DISPLAY 0.680851 (2790 2535);
PAINT MONO (2790 2535);
FORCEPROP 2 LAST CDS_LIB pure_quanta
J 0
(4000 1800);
DISPLAY INVISIBLE (4000 1800);
FORCEPROP 1 LAST NEEDS_NO_SIZE TRUE
J 0
(4000 1800);
DISPLAY 0.723404 (4000 1800);
PAINT GREEN (4000 1800);
DISPLAY INVISIBLE (4000 1800);
FORCEPROP 1 LAST CDS_LMAN_SYM_OUTLINE -1050,2150,1050,-2100
J 0
(4000 1800);
DISPLAY 0.468085 (4000 1800);
PAINT GREEN (4000 1800);
DISPLAY INVISIBLE (4000 1800);
FORCEPROP 0 LAST CDS_LOCATION U1
J 0
(2950 4275);
DISPLAY 1.021277 (2950 4275);
DISPLAY INVISIBLE (2950 4275);
FORCEPROP 0 LAST $SEC 33
J 0
(2950 4275);
DISPLAY 0.680851 (2950 4275);
PAINT MONO (2950 4275);
DISPLAY INVISIBLE (2950 4275);
FORCEPROP 2 LAST CDS_SEC 33
J 0
(2950 4275);
DISPLAY 1.021277 (2950 4275);
DISPLAY INVISIBLE (2950 4275);
FORCEPROP 1 LAST PATH I8
J 0
(4000 1800);
DISPLAY 0.723404 (4000 1800);
PAINT GREEN (4000 1800);
DISPLAY INVISIBLE (4000 1800);
FORCEADD UNIVERSAL_GND..1
(5450 -725);
FORCEPROP 3 LASTPIN (5450 -675) SIG_NAME GND\g
J 0
(5460 -665);
DISPLAY 0.659574 (5460 -665);
PAINT MONO (5460 -665);
DISPLAY INVISIBLE (5460 -665);
FORCEPROP 2 LAST CDS_LIB logical_power
J 0
(5450 -725);
PAINT MONO (5450 -725);
DISPLAY INVISIBLE (5450 -725);
FORCEPROP 1 LAST HDL_POWER GND
J 1
(5475 -800);
DISPLAY 0.872340 (5475 -800);
PAINT GREEN (5475 -800);
DISPLAY INVISIBLE (5475 -800);
FORCEPROP 1 LAST PATH I9
J 0
(5525 -725);
DISPLAY 0.872340 (5525 -725);
PAINT AQUA (5525 -725);
DISPLAY INVISIBLE (5525 -725);
FORCEADD QUANTA_TITLE_BLOCK_C..1
(5650 -1575);
FORCEPROP 0 LAST CDS_CON_LAST_MODIFIED Fri Aug 25 14:00:51 2023
J 0
(3765 -1560);
PAINT MONO (3765 -1560);
DISPLAY INVISIBLE (3765 -1560);
FORCEPROP 2 LAST CUSTOM_TXT_CDS <XR_PAGE_TITLE>
J 0
(-2240 3675);
DISPLAY 0.638298 (-2240 3675);
PAINT PINK (-2240 3675);
DISPLAY INVISIBLE (-2240 3675);
FORCEPROP 2 LAST CUSTOM_TXT_CDS <CON_PAGE_NUM> OF <CON_TOTAL_PAGES>
J 0
(5200 -1575);
DISPLAY 0.978723 (5200 -1575);
FORCEPROP 2 LAST CUSTOM_TXT_CDS <Q_REV>
J 0
(5466 -1472);
DISPLAY 1.212766 (5466 -1472);
FORCEPROP 2 LAST CUSTOM_TXT_CDS <CON_LAST_MODIFIED>
J 0
(3765 -1560);
DISPLAY 0.978723 (3765 -1560);
FORCEPROP 2 LAST CUSTOM_TXT_CDS <Q_NUMBER>
J 0
(4247 -1472);
DISPLAY 1.212766 (4247 -1472);
FORCEPROP 2 LAST CUSTOM_TXT_CDS <Q_PROJ>
J 0
(3268 -1473);
DISPLAY 1.212766 (3268 -1473);
FORCEPROP 1 LAST CUSTOM_TXT_CDS <NAME_2>
J 0
(2475 -1525);
FORCEPROP 1 LAST CUSTOM_TXT_CDS <NAME_1>
J 0
(2475 -1400);
FORCEPROP 1 LAST Q_TITLE SPR CPU1 POWER - GND (27 OF 30)
J 0
(-3716 -1549);
DISPLAY 1.957447 (-3716 -1549);
PAINT GREEN (-3716 -1549);
FORCEPROP 1 LAST Q_DEPT 
J 1
(1887 -1526);
DISPLAY 1.957447 (1887 -1526);
PAINT GREEN (1887 -1526);
FORCEPROP 1 LAST COMMENT_BODY TRUE
J 0
(5662 -1588);
DISPLAY 0.978723 (5662 -1588);
PAINT GREEN (5662 -1588);
DISPLAY INVISIBLE (5662 -1588);
FORCEPROP 2 LAST CDS_XR_PAGE_TITLE CR-70 : @S9S_MB_2U_LIB.S9S_MB_2U(SCH_1):PAGE70
J 0
(-2240 3675);
DISPLAY 0.638298 (-2240 3675);
PAINT PINK (-2240 3675);
DISPLAY INVISIBLE (-2240 3675);
FORCEPROP 2 LAST CDS_LIB pure_quanta
J 0
(5650 -1575);
PAINT MONO (5650 -1575);
DISPLAY INVISIBLE (5650 -1575);
FORCEPROP 1 LAST CDS_LMAN_SYM_OUTLINE -9475,6775,100,-125
J 0
(5650 -1575);
DISPLAY 0.468085 (5650 -1575);
PAINT GREEN (5650 -1575);
DISPLAY INVISIBLE (5650 -1575);
FORCEPROP 2 LAST PAGE_BORDER TRUE
J 0
(-2240 3675);
DISPLAY 0.638298 (-2240 3675);
PAINT PINK (-2240 3675);
DISPLAY INVISIBLE (-2240 3675);
WIRE 16 -1 (5450 -175)(5450 -675);
WIRE 16 -1 (5450 -125)(5450 -175);
WIRE 16 -1 (5200 -175)(5450 -175);
WIRE 16 -1 (2550 -175)(2550 -675);
WIRE 16 -1 (2550 -125)(2550 -175);
WIRE 16 -1 (2550 -175)(2800 -175);
WIRE 16 -1 (2425 -175)(2425 -675);
WIRE 16 -1 (2425 -125)(2425 -175);
WIRE 16 -1 (2175 -175)(2425 -175);
WIRE 16 -1 (-475 -175)(-475 -675);
WIRE 16 -1 (-475 -125)(-475 -175);
WIRE 16 -1 (-475 -175)(-225 -175);
WIRE 16 -1 (-625 -175)(-625 -675);
WIRE 16 -1 (-625 -125)(-625 -175);
WIRE 16 -1 (-875 -175)(-625 -175);
WIRE 16 -1 (-3525 -175)(-3525 -675);
WIRE 16 -1 (-3525 -125)(-3525 -175);
WIRE 16 -1 (-3525 -175)(-3275 -175);
WIRE 16 -1 (-625 3775)(-875 3775);
WIRE 16 -1 (-625 3725)(-875 3725);
WIRE 16 -1 (-625 3775)(-625 3725);
WIRE 16 -1 (-625 3675)(-875 3675);
WIRE 16 -1 (-625 3725)(-625 3675);
WIRE 16 -1 (-625 3625)(-875 3625);
WIRE 16 -1 (-625 3675)(-625 3625);
WIRE 16 -1 (-875 3575)(-625 3575);
WIRE 16 -1 (-625 3575)(-625 3625);
WIRE 16 -1 (-625 3525)(-875 3525);
WIRE 16 -1 (-625 3525)(-625 3575);
WIRE 16 -1 (-625 3475)(-875 3475);
WIRE 16 -1 (-625 3525)(-625 3475);
WIRE 16 -1 (-625 3425)(-875 3425);
WIRE 16 -1 (-625 3475)(-625 3425);
WIRE 16 -1 (-625 3375)(-875 3375);
WIRE 16 -1 (-625 3425)(-625 3375);
WIRE 16 -1 (-625 3325)(-875 3325);
WIRE 16 -1 (-625 3375)(-625 3325);
WIRE 16 -1 (-625 3275)(-875 3275);
WIRE 16 -1 (-625 3325)(-625 3275);
WIRE 16 -1 (-625 3225)(-875 3225);
WIRE 16 -1 (-625 3275)(-625 3225);
WIRE 16 -1 (-625 3175)(-875 3175);
WIRE 16 -1 (-625 3225)(-625 3175);
WIRE 16 -1 (-625 3125)(-875 3125);
WIRE 16 -1 (-625 3175)(-625 3125);
WIRE 16 -1 (-875 3075)(-625 3075);
WIRE 16 -1 (-625 3125)(-625 3075);
WIRE 16 -1 (-875 3025)(-625 3025);
WIRE 16 -1 (-625 3075)(-625 3025);
WIRE 16 -1 (-875 2975)(-625 2975);
WIRE 16 -1 (-625 3025)(-625 2975);
WIRE 16 -1 (-875 2925)(-625 2925);
WIRE 16 -1 (-625 2975)(-625 2925);
WIRE 16 -1 (-875 2875)(-625 2875);
WIRE 16 -1 (-625 2925)(-625 2875);
WIRE 16 -1 (-875 2825)(-625 2825);
WIRE 16 -1 (-625 2875)(-625 2825);
WIRE 16 -1 (-875 2775)(-625 2775);
WIRE 16 -1 (-625 2825)(-625 2775);
WIRE 16 -1 (-875 2725)(-625 2725);
WIRE 16 -1 (-625 2725)(-625 2775);
WIRE 16 -1 (-875 2675)(-625 2675);
WIRE 16 -1 (-625 2725)(-625 2675);
WIRE 16 -1 (-625 2625)(-875 2625);
WIRE 16 -1 (-625 2675)(-625 2625);
WIRE 16 -1 (-625 2575)(-875 2575);
WIRE 16 -1 (-625 2625)(-625 2575);
WIRE 16 -1 (-625 2525)(-875 2525);
WIRE 16 -1 (-625 2575)(-625 2525);
WIRE 16 -1 (-625 2475)(-875 2475);
WIRE 16 -1 (-625 2525)(-625 2475);
WIRE 16 -1 (-875 2425)(-625 2425);
WIRE 16 -1 (-625 2425)(-625 2475);
WIRE 16 -1 (-625 2375)(-875 2375);
WIRE 16 -1 (-625 2375)(-625 2425);
WIRE 16 -1 (-625 2325)(-875 2325);
WIRE 16 -1 (-625 2375)(-625 2325);
WIRE 16 -1 (-625 2275)(-875 2275);
WIRE 16 -1 (-625 2325)(-625 2275);
WIRE 16 -1 (-875 -125)(-625 -125);
WIRE 16 -1 (-875 -75)(-625 -75);
WIRE 16 -1 (-625 -125)(-625 -75);
WIRE 16 -1 (-625 2225)(-875 2225);
WIRE 16 -1 (-625 2275)(-625 2225);
WIRE 16 -1 (-625 2175)(-875 2175);
WIRE 16 -1 (-625 2225)(-625 2175);
WIRE 16 -1 (-875 -25)(-625 -25);
WIRE 16 -1 (-625 -25)(-625 -75);
WIRE 16 -1 (-875 25)(-625 25);
WIRE 16 -1 (-625 25)(-625 -25);
WIRE 16 -1 (-625 2125)(-875 2125);
WIRE 16 -1 (-625 2175)(-625 2125);
WIRE 16 -1 (-625 2075)(-875 2075);
WIRE 16 -1 (-625 2125)(-625 2075);
WIRE 16 -1 (-875 75)(-625 75);
WIRE 16 -1 (-625 75)(-625 25);
WIRE 16 -1 (-875 125)(-625 125);
WIRE 16 -1 (-625 125)(-625 75);
WIRE 16 -1 (-625 2025)(-875 2025);
WIRE 16 -1 (-625 2075)(-625 2025);
WIRE 16 -1 (-625 1975)(-875 1975);
WIRE 16 -1 (-625 2025)(-625 1975);
WIRE 16 -1 (-875 175)(-625 175);
WIRE 16 -1 (-625 175)(-625 125);
WIRE 16 -1 (-875 225)(-625 225);
WIRE 16 -1 (-625 225)(-625 175);
WIRE 16 -1 (-875 1925)(-625 1925);
WIRE 16 -1 (-625 1975)(-625 1925);
WIRE 16 -1 (-875 1875)(-625 1875);
WIRE 16 -1 (-625 1925)(-625 1875);
WIRE 16 -1 (-625 275)(-875 275);
WIRE 16 -1 (-625 275)(-625 225);
WIRE 16 -1 (-625 325)(-875 325);
WIRE 16 -1 (-625 325)(-625 275);
WIRE 16 -1 (-875 1825)(-625 1825);
WIRE 16 -1 (-625 1875)(-625 1825);
WIRE 16 -1 (-875 1775)(-625 1775);
WIRE 16 -1 (-625 1825)(-625 1775);
WIRE 16 -1 (-625 375)(-875 375);
WIRE 16 -1 (-625 375)(-625 325);
WIRE 16 -1 (-875 425)(-625 425);
WIRE 16 -1 (-625 375)(-625 425);
WIRE 16 -1 (-875 1725)(-625 1725);
WIRE 16 -1 (-625 1775)(-625 1725);
WIRE 16 -1 (-875 1675)(-625 1675);
WIRE 16 -1 (-625 1725)(-625 1675);
WIRE 16 -1 (-625 475)(-875 475);
WIRE 16 -1 (-625 425)(-625 475);
WIRE 16 -1 (-625 525)(-875 525);
WIRE 16 -1 (-625 525)(-625 475);
WIRE 16 -1 (-875 1625)(-625 1625);
WIRE 16 -1 (-625 1675)(-625 1625);
WIRE 16 -1 (-875 1575)(-625 1575);
WIRE 16 -1 (-625 1575)(-625 1625);
WIRE 16 -1 (-625 575)(-875 575);
WIRE 16 -1 (-625 575)(-625 525);
WIRE 16 -1 (-625 625)(-875 625);
WIRE 16 -1 (-625 625)(-625 575);
WIRE 16 -1 (-875 1525)(-625 1525);
WIRE 16 -1 (-625 1575)(-625 1525);
WIRE 16 -1 (-625 1475)(-875 1475);
WIRE 16 -1 (-625 1525)(-625 1475);
WIRE 16 -1 (-875 675)(-625 675);
WIRE 16 -1 (-625 675)(-625 625);
WIRE 16 -1 (-875 725)(-625 725);
WIRE 16 -1 (-625 725)(-625 675);
WIRE 16 -1 (-625 1425)(-875 1425);
WIRE 16 -1 (-625 1475)(-625 1425);
WIRE 16 -1 (-625 1375)(-875 1375);
WIRE 16 -1 (-625 1425)(-625 1375);
WIRE 16 -1 (-875 775)(-625 775);
WIRE 16 -1 (-625 725)(-625 775);
WIRE 16 -1 (-875 825)(-625 825);
WIRE 16 -1 (-625 825)(-625 775);
WIRE 16 -1 (-625 1325)(-875 1325);
WIRE 16 -1 (-625 1375)(-625 1325);
WIRE 16 -1 (-875 1275)(-625 1275);
WIRE 16 -1 (-625 1275)(-625 1325);
WIRE 16 -1 (-875 875)(-625 875);
WIRE 16 -1 (-625 875)(-625 825);
WIRE 16 -1 (-875 925)(-625 925);
WIRE 16 -1 (-625 925)(-625 875);
WIRE 16 -1 (-625 1225)(-875 1225);
WIRE 16 -1 (-625 1225)(-625 1275);
WIRE 16 -1 (-625 1175)(-875 1175);
WIRE 16 -1 (-625 1225)(-625 1175);
WIRE 16 -1 (-875 975)(-625 975);
WIRE 16 -1 (-625 975)(-625 925);
WIRE 16 -1 (-875 1025)(-625 1025);
WIRE 16 -1 (-625 1025)(-625 975);
WIRE 16 -1 (-625 1125)(-875 1125);
WIRE 16 -1 (-625 1175)(-625 1125);
WIRE 16 -1 (-625 1125)(-625 1075);
WIRE 16 -1 (-625 1075)(-625 1025);
WIRE 16 -1 (-875 1075)(-625 1075);
WIRE 16 -1 (2425 3775)(2175 3775);
WIRE 16 -1 (2425 3725)(2175 3725);
WIRE 16 -1 (2425 3775)(2425 3725);
WIRE 16 -1 (2425 3675)(2175 3675);
WIRE 16 -1 (2425 3725)(2425 3675);
WIRE 16 -1 (2425 3625)(2175 3625);
WIRE 16 -1 (2425 3675)(2425 3625);
WIRE 16 -1 (2175 3575)(2425 3575);
WIRE 16 -1 (2425 3575)(2425 3625);
WIRE 16 -1 (2425 3525)(2175 3525);
WIRE 16 -1 (2425 3525)(2425 3575);
WIRE 16 -1 (2425 3475)(2175 3475);
WIRE 16 -1 (2425 3525)(2425 3475);
WIRE 16 -1 (2425 3425)(2175 3425);
WIRE 16 -1 (2425 3475)(2425 3425);
WIRE 16 -1 (2425 3375)(2175 3375);
WIRE 16 -1 (2425 3425)(2425 3375);
WIRE 16 -1 (2425 3325)(2175 3325);
WIRE 16 -1 (2425 3375)(2425 3325);
WIRE 16 -1 (2425 3275)(2175 3275);
WIRE 16 -1 (2425 3325)(2425 3275);
WIRE 16 -1 (2425 3225)(2175 3225);
WIRE 16 -1 (2425 3275)(2425 3225);
WIRE 16 -1 (2425 3175)(2175 3175);
WIRE 16 -1 (2425 3225)(2425 3175);
WIRE 16 -1 (2425 3125)(2175 3125);
WIRE 16 -1 (2425 3175)(2425 3125);
WIRE 16 -1 (2175 3075)(2425 3075);
WIRE 16 -1 (2425 3125)(2425 3075);
WIRE 16 -1 (2175 3025)(2425 3025);
WIRE 16 -1 (2425 3075)(2425 3025);
WIRE 16 -1 (2175 2975)(2425 2975);
WIRE 16 -1 (2425 3025)(2425 2975);
WIRE 16 -1 (2175 2925)(2425 2925);
WIRE 16 -1 (2425 2975)(2425 2925);
WIRE 16 -1 (2175 2875)(2425 2875);
WIRE 16 -1 (2425 2925)(2425 2875);
WIRE 16 -1 (2175 2825)(2425 2825);
WIRE 16 -1 (2425 2875)(2425 2825);
WIRE 16 -1 (2175 2775)(2425 2775);
WIRE 16 -1 (2425 2825)(2425 2775);
WIRE 16 -1 (2175 2725)(2425 2725);
WIRE 16 -1 (2425 2725)(2425 2775);
WIRE 16 -1 (2175 2675)(2425 2675);
WIRE 16 -1 (2425 2725)(2425 2675);
WIRE 16 -1 (2425 2625)(2175 2625);
WIRE 16 -1 (2425 2675)(2425 2625);
WIRE 16 -1 (2425 2575)(2175 2575);
WIRE 16 -1 (2425 2625)(2425 2575);
WIRE 16 -1 (2425 2525)(2175 2525);
WIRE 16 -1 (2425 2575)(2425 2525);
WIRE 16 -1 (2425 2475)(2175 2475);
WIRE 16 -1 (2425 2525)(2425 2475);
WIRE 16 -1 (2175 2425)(2425 2425);
WIRE 16 -1 (2425 2425)(2425 2475);
WIRE 16 -1 (2425 2375)(2175 2375);
WIRE 16 -1 (2425 2375)(2425 2425);
WIRE 16 -1 (2425 2325)(2175 2325);
WIRE 16 -1 (2425 2375)(2425 2325);
WIRE 16 -1 (2425 2275)(2175 2275);
WIRE 16 -1 (2425 2325)(2425 2275);
WIRE 16 -1 (2425 2225)(2175 2225);
WIRE 16 -1 (2425 2275)(2425 2225);
WIRE 16 -1 (2425 2175)(2175 2175);
WIRE 16 -1 (2425 2225)(2425 2175);
WIRE 16 -1 (2425 2125)(2175 2125);
WIRE 16 -1 (2425 2175)(2425 2125);
WIRE 16 -1 (2425 2075)(2175 2075);
WIRE 16 -1 (2425 2125)(2425 2075);
WIRE 16 -1 (2425 2025)(2175 2025);
WIRE 16 -1 (2425 2075)(2425 2025);
WIRE 16 -1 (2425 1975)(2175 1975);
WIRE 16 -1 (2425 2025)(2425 1975);
WIRE 16 -1 (2175 1925)(2425 1925);
WIRE 16 -1 (2425 1975)(2425 1925);
WIRE 16 -1 (2175 1875)(2425 1875);
WIRE 16 -1 (2425 1925)(2425 1875);
WIRE 16 -1 (2175 1825)(2425 1825);
WIRE 16 -1 (2425 1875)(2425 1825);
WIRE 16 -1 (2175 1775)(2425 1775);
WIRE 16 -1 (2425 1825)(2425 1775);
WIRE 16 -1 (2175 1725)(2425 1725);
WIRE 16 -1 (2425 1775)(2425 1725);
WIRE 16 -1 (2175 1675)(2425 1675);
WIRE 16 -1 (2425 1725)(2425 1675);
WIRE 16 -1 (2175 1625)(2425 1625);
WIRE 16 -1 (2425 1675)(2425 1625);
WIRE 16 -1 (2175 1575)(2425 1575);
WIRE 16 -1 (2425 1575)(2425 1625);
WIRE 16 -1 (2175 1525)(2425 1525);
WIRE 16 -1 (2425 1575)(2425 1525);
WIRE 16 -1 (2425 1475)(2175 1475);
WIRE 16 -1 (2425 1525)(2425 1475);
WIRE 16 -1 (2425 1425)(2175 1425);
WIRE 16 -1 (2425 1475)(2425 1425);
WIRE 16 -1 (2425 1375)(2175 1375);
WIRE 16 -1 (2425 1425)(2425 1375);
WIRE 16 -1 (2425 1325)(2175 1325);
WIRE 16 -1 (2425 1375)(2425 1325);
WIRE 16 -1 (2175 1275)(2425 1275);
WIRE 16 -1 (2425 1275)(2425 1325);
WIRE 16 -1 (2425 1225)(2175 1225);
WIRE 16 -1 (2425 1225)(2425 1275);
WIRE 16 -1 (2425 1175)(2175 1175);
WIRE 16 -1 (2425 1225)(2425 1175);
WIRE 16 -1 (2425 1125)(2175 1125);
WIRE 16 -1 (2425 1175)(2425 1125);
WIRE 16 -1 (2175 1075)(2425 1075);
WIRE 16 -1 (2425 1125)(2425 1075);
WIRE 16 -1 (2175 1025)(2425 1025);
WIRE 16 -1 (2425 1075)(2425 1025);
WIRE 16 -1 (2175 975)(2425 975);
WIRE 16 -1 (2425 1025)(2425 975);
WIRE 16 -1 (2175 925)(2425 925);
WIRE 16 -1 (2425 975)(2425 925);
WIRE 16 -1 (2175 875)(2425 875);
WIRE 16 -1 (2425 925)(2425 875);
WIRE 16 -1 (2175 825)(2425 825);
WIRE 16 -1 (2425 875)(2425 825);
WIRE 16 -1 (2175 775)(2425 775);
WIRE 16 -1 (2425 825)(2425 775);
WIRE 16 -1 (2175 725)(2425 725);
WIRE 16 -1 (2425 725)(2425 775);
WIRE 16 -1 (2175 675)(2425 675);
WIRE 16 -1 (2425 725)(2425 675);
WIRE 16 -1 (2425 625)(2175 625);
WIRE 16 -1 (2425 675)(2425 625);
WIRE 16 -1 (2425 575)(2175 575);
WIRE 16 -1 (2425 625)(2425 575);
WIRE 16 -1 (2425 525)(2175 525);
WIRE 16 -1 (2425 575)(2425 525);
WIRE 16 -1 (2425 475)(2175 475);
WIRE 16 -1 (2425 525)(2425 475);
WIRE 16 -1 (2175 425)(2425 425);
WIRE 16 -1 (2425 425)(2425 475);
WIRE 16 -1 (2425 375)(2175 375);
WIRE 16 -1 (2425 375)(2425 425);
WIRE 16 -1 (2425 325)(2175 325);
WIRE 16 -1 (2425 375)(2425 325);
WIRE 16 -1 (2425 275)(2175 275);
WIRE 16 -1 (2425 325)(2425 275);
WIRE 16 -1 (2175 225)(2425 225);
WIRE 16 -1 (2425 275)(2425 225);
WIRE 16 -1 (2175 175)(2425 175);
WIRE 16 -1 (2425 225)(2425 175);
WIRE 16 -1 (2175 125)(2425 125);
WIRE 16 -1 (2425 175)(2425 125);
WIRE 16 -1 (2175 75)(2425 75);
WIRE 16 -1 (2425 125)(2425 75);
WIRE 16 -1 (2175 25)(2425 25);
WIRE 16 -1 (2425 75)(2425 25);
WIRE 16 -1 (2175 -25)(2425 -25);
WIRE 16 -1 (2425 25)(2425 -25);
WIRE 16 -1 (2175 -75)(2425 -75);
WIRE 16 -1 (2425 -25)(2425 -75);
WIRE 16 -1 (2425 -125)(2425 -75);
WIRE 16 -1 (2175 -125)(2425 -125);
WIRE 16 -1 (-3275 3775)(-3525 3775);
WIRE 16 -1 (-3525 3775)(-3525 3725);
WIRE 16 -1 (-3275 3725)(-3525 3725);
WIRE 16 -1 (-3525 3725)(-3525 3675);
WIRE 16 -1 (-3275 3675)(-3525 3675);
WIRE 16 -1 (-3525 3675)(-3525 3625);
WIRE 16 -1 (-3275 3625)(-3525 3625);
WIRE 16 -1 (-3275 3575)(-3525 3575);
WIRE 16 -1 (-3525 3625)(-3525 3575);
WIRE 16 -1 (-3525 3575)(-3525 3525);
WIRE 16 -1 (-3275 3525)(-3525 3525);
WIRE 16 -1 (-3525 3525)(-3525 3475);
WIRE 16 -1 (-3275 3475)(-3525 3475);
WIRE 16 -1 (-3525 3475)(-3525 3425);
WIRE 16 -1 (-3275 3425)(-3525 3425);
WIRE 16 -1 (-3525 3425)(-3525 3375);
WIRE 16 -1 (-3275 3375)(-3525 3375);
WIRE 16 -1 (-3525 3375)(-3525 3325);
WIRE 16 -1 (-3275 3325)(-3525 3325);
WIRE 16 -1 (-3525 3325)(-3525 3275);
WIRE 16 -1 (-3275 3275)(-3525 3275);
WIRE 16 -1 (-3525 3275)(-3525 3225);
WIRE 16 -1 (-3275 3225)(-3525 3225);
WIRE 16 -1 (-3525 3225)(-3525 3175);
WIRE 16 -1 (-3275 3175)(-3525 3175);
WIRE 16 -1 (-3525 3175)(-3525 3125);
WIRE 16 -1 (-3275 3125)(-3525 3125);
WIRE 16 -1 (-3525 3125)(-3525 3075);
WIRE 16 -1 (-3525 3075)(-3275 3075);
WIRE 16 -1 (-3525 3025)(-3275 3025);
WIRE 16 -1 (-3525 3075)(-3525 3025);
WIRE 16 -1 (-3525 3025)(-3525 2975);
WIRE 16 -1 (-3525 2975)(-3275 2975);
WIRE 16 -1 (-3525 2975)(-3525 2925);
WIRE 16 -1 (-3525 2925)(-3275 2925);
WIRE 16 -1 (-3525 2925)(-3525 2875);
WIRE 16 -1 (-3525 2875)(-3275 2875);
WIRE 16 -1 (-3525 2875)(-3525 2825);
WIRE 16 -1 (-3525 2825)(-3275 2825);
WIRE 16 -1 (-3525 2825)(-3525 2775);
WIRE 16 -1 (-3525 2775)(-3275 2775);
WIRE 16 -1 (-3525 2775)(-3525 2725);
WIRE 16 -1 (-3525 2725)(-3275 2725);
WIRE 16 -1 (-3525 2725)(-3525 2675);
WIRE 16 -1 (-3525 2675)(-3275 2675);
WIRE 16 -1 (-3525 2675)(-3525 2625);
WIRE 16 -1 (-3525 2625)(-3275 2625);
WIRE 16 -1 (-3525 2625)(-3525 2575);
WIRE 16 -1 (-3525 2575)(-3275 2575);
WIRE 16 -1 (-3525 2525)(-3275 2525);
WIRE 16 -1 (-3525 2575)(-3525 2525);
WIRE 16 -1 (-3525 2525)(-3525 2475);
WIRE 16 -1 (-3525 2475)(-3275 2475);
WIRE 16 -1 (-3525 2475)(-3525 2425);
WIRE 16 -1 (-3525 2425)(-3275 2425);
WIRE 16 -1 (-3525 2425)(-3525 2375);
WIRE 16 -1 (-3525 2375)(-3275 2375);
WIRE 16 -1 (-3525 2375)(-3525 2325);
WIRE 16 -1 (-3525 2325)(-3275 2325);
WIRE 16 -1 (-3525 2325)(-3525 2275);
WIRE 16 -1 (-3525 2275)(-3275 2275);
WIRE 16 -1 (-3525 2275)(-3525 2225);
WIRE 16 -1 (-3525 2225)(-3275 2225);
WIRE 16 -1 (-3525 2225)(-3525 2175);
WIRE 16 -1 (-3525 2175)(-3275 2175);
WIRE 16 -1 (-3525 2175)(-3525 2125);
WIRE 16 -1 (-3525 2125)(-3275 2125);
WIRE 16 -1 (-3525 2125)(-3525 2075);
WIRE 16 -1 (-3525 2075)(-3275 2075);
WIRE 16 -1 (-3525 2025)(-3275 2025);
WIRE 16 -1 (-3525 2075)(-3525 2025);
WIRE 16 -1 (-3525 2025)(-3525 1975);
WIRE 16 -1 (-3525 1975)(-3275 1975);
WIRE 16 -1 (-3525 1975)(-3525 1925);
WIRE 16 -1 (-3525 1925)(-3275 1925);
WIRE 16 -1 (-3525 1925)(-3525 1875);
WIRE 16 -1 (-3525 1875)(-3275 1875);
WIRE 16 -1 (-3525 1875)(-3525 1825);
WIRE 16 -1 (-3525 1825)(-3275 1825);
WIRE 16 -1 (-3525 1825)(-3525 1775);
WIRE 16 -1 (-3525 1775)(-3275 1775);
WIRE 16 -1 (-3525 1775)(-3525 1725);
WIRE 16 -1 (-3275 1725)(-3525 1725);
WIRE 16 -1 (-3525 1725)(-3525 1675);
WIRE 16 -1 (-3525 1675)(-3275 1675);
WIRE 16 -1 (-3525 1675)(-3525 1625);
WIRE 16 -1 (-3525 1625)(-3275 1625);
WIRE 16 -1 (-3525 1625)(-3525 1575);
WIRE 16 -1 (-3525 1575)(-3275 1575);
WIRE 16 -1 (-3525 1525)(-3275 1525);
WIRE 16 -1 (-3525 1575)(-3525 1525);
WIRE 16 -1 (-3525 1525)(-3525 1475);
WIRE 16 -1 (-3525 1475)(-3275 1475);
WIRE 16 -1 (-3525 1475)(-3525 1425);
WIRE 16 -1 (-3525 1425)(-3275 1425);
WIRE 16 -1 (-3525 1425)(-3525 1375);
WIRE 16 -1 (-3525 1375)(-3275 1375);
WIRE 16 -1 (-3525 1375)(-3525 1325);
WIRE 16 -1 (-3525 1325)(-3275 1325);
WIRE 16 -1 (-3525 1325)(-3525 1275);
WIRE 16 -1 (-3525 1275)(-3275 1275);
WIRE 16 -1 (-3525 1275)(-3525 1225);
WIRE 16 -1 (-3525 1225)(-3275 1225);
WIRE 16 -1 (-3525 1225)(-3525 1175);
WIRE 16 -1 (-3525 1175)(-3275 1175);
WIRE 16 -1 (-3525 1175)(-3525 1125);
WIRE 16 -1 (-3525 1125)(-3275 1125);
WIRE 16 -1 (-3525 1125)(-3525 1075);
WIRE 16 -1 (-3525 1075)(-3275 1075);
WIRE 16 -1 (-3525 1075)(-3525 1025);
WIRE 16 -1 (-3525 1025)(-3275 1025);
WIRE 16 -1 (-3525 975)(-3275 975);
WIRE 16 -1 (-3525 1025)(-3525 975);
WIRE 16 -1 (-3525 975)(-3525 925);
WIRE 16 -1 (-3525 925)(-3275 925);
WIRE 16 -1 (-3525 925)(-3525 875);
WIRE 16 -1 (-3525 875)(-3275 875);
WIRE 16 -1 (-3525 875)(-3525 825);
WIRE 16 -1 (-3525 825)(-3275 825);
WIRE 16 -1 (-3525 825)(-3525 775);
WIRE 16 -1 (-3525 775)(-3275 775);
WIRE 16 -1 (-3525 775)(-3525 725);
WIRE 16 -1 (-3275 725)(-3525 725);
WIRE 16 -1 (-3525 725)(-3525 675);
WIRE 16 -1 (-3525 675)(-3275 675);
WIRE 16 -1 (-3525 675)(-3525 625);
WIRE 16 -1 (-3525 625)(-3275 625);
WIRE 16 -1 (-3525 625)(-3525 575);
WIRE 16 -1 (-3525 575)(-3275 575);
WIRE 16 -1 (-3525 575)(-3525 525);
WIRE 16 -1 (-3525 525)(-3275 525);
WIRE 16 -1 (-3525 475)(-3275 475);
WIRE 16 -1 (-3525 525)(-3525 475);
WIRE 16 -1 (-3525 475)(-3525 425);
WIRE 16 -1 (-3275 425)(-3525 425);
WIRE 16 -1 (-3525 425)(-3525 375);
WIRE 16 -1 (-3525 375)(-3275 375);
WIRE 16 -1 (-3525 375)(-3525 325);
WIRE 16 -1 (-3525 325)(-3275 325);
WIRE 16 -1 (-3525 325)(-3525 275);
WIRE 16 -1 (-3525 275)(-3275 275);
WIRE 16 -1 (-3525 275)(-3525 225);
WIRE 16 -1 (-3525 225)(-3275 225);
WIRE 16 -1 (-3525 225)(-3525 175);
WIRE 16 -1 (-3525 175)(-3275 175);
WIRE 16 -1 (-3525 175)(-3525 125);
WIRE 16 -1 (-3525 125)(-3275 125);
WIRE 16 -1 (-3525 125)(-3525 75);
WIRE 16 -1 (-3275 75)(-3525 75);
WIRE 16 -1 (-3525 75)(-3525 25);
WIRE 16 -1 (-3525 25)(-3275 25);
WIRE 16 -1 (-3525 -25)(-3275 -25);
WIRE 16 -1 (-3525 25)(-3525 -25);
WIRE 16 -1 (-3525 -25)(-3525 -75);
WIRE 16 -1 (-3525 -75)(-3275 -75);
WIRE 16 -1 (-3525 -75)(-3525 -125);
WIRE 16 -1 (-3525 -125)(-3275 -125);
WIRE 16 -1 (-225 3775)(-475 3775);
WIRE 16 -1 (-475 3775)(-475 3725);
WIRE 16 -1 (-225 3725)(-475 3725);
WIRE 16 -1 (-475 3725)(-475 3675);
WIRE 16 -1 (-225 3675)(-475 3675);
WIRE 16 -1 (-475 3675)(-475 3625);
WIRE 16 -1 (-225 3625)(-475 3625);
WIRE 16 -1 (-225 3575)(-475 3575);
WIRE 16 -1 (-475 3625)(-475 3575);
WIRE 16 -1 (-475 3575)(-475 3525);
WIRE 16 -1 (-225 3525)(-475 3525);
WIRE 16 -1 (-475 3525)(-475 3475);
WIRE 16 -1 (-225 3475)(-475 3475);
WIRE 16 -1 (-475 3475)(-475 3425);
WIRE 16 -1 (-225 3425)(-475 3425);
WIRE 16 -1 (-475 3425)(-475 3375);
WIRE 16 -1 (-225 3375)(-475 3375);
WIRE 16 -1 (-475 3375)(-475 3325);
WIRE 16 -1 (-225 3325)(-475 3325);
WIRE 16 -1 (-475 3325)(-475 3275);
WIRE 16 -1 (-225 3275)(-475 3275);
WIRE 16 -1 (-475 3275)(-475 3225);
WIRE 16 -1 (-225 3225)(-475 3225);
WIRE 16 -1 (-475 3225)(-475 3175);
WIRE 16 -1 (-225 3175)(-475 3175);
WIRE 16 -1 (-475 3175)(-475 3125);
WIRE 16 -1 (-225 3125)(-475 3125);
WIRE 16 -1 (-475 3125)(-475 3075);
WIRE 16 -1 (-475 3075)(-225 3075);
WIRE 16 -1 (-475 3025)(-225 3025);
WIRE 16 -1 (-475 3075)(-475 3025);
WIRE 16 -1 (-475 3025)(-475 2975);
WIRE 16 -1 (-475 2975)(-225 2975);
WIRE 16 -1 (-475 2975)(-475 2925);
WIRE 16 -1 (-475 2925)(-225 2925);
WIRE 16 -1 (-475 2925)(-475 2875);
WIRE 16 -1 (-475 2875)(-225 2875);
WIRE 16 -1 (-475 2875)(-475 2825);
WIRE 16 -1 (-475 2825)(-225 2825);
WIRE 16 -1 (-475 2825)(-475 2775);
WIRE 16 -1 (-475 2775)(-225 2775);
WIRE 16 -1 (-475 2775)(-475 2725);
WIRE 16 -1 (-475 2725)(-225 2725);
WIRE 16 -1 (-475 2725)(-475 2675);
WIRE 16 -1 (-475 2675)(-225 2675);
WIRE 16 -1 (-475 2675)(-475 2625);
WIRE 16 -1 (-475 2625)(-225 2625);
WIRE 16 -1 (-475 2625)(-475 2575);
WIRE 16 -1 (-475 2575)(-225 2575);
WIRE 16 -1 (-475 2525)(-225 2525);
WIRE 16 -1 (-475 2575)(-475 2525);
WIRE 16 -1 (-475 2525)(-475 2475);
WIRE 16 -1 (-475 2475)(-225 2475);
WIRE 16 -1 (-475 2475)(-475 2425);
WIRE 16 -1 (-475 2425)(-225 2425);
WIRE 16 -1 (-475 2425)(-475 2375);
WIRE 16 -1 (-475 2375)(-225 2375);
WIRE 16 -1 (-475 2375)(-475 2325);
WIRE 16 -1 (-475 2325)(-225 2325);
WIRE 16 -1 (-475 2325)(-475 2275);
WIRE 16 -1 (-475 2275)(-225 2275);
WIRE 16 -1 (-475 2275)(-475 2225);
WIRE 16 -1 (-475 2225)(-225 2225);
WIRE 16 -1 (-475 2225)(-475 2175);
WIRE 16 -1 (-475 2175)(-225 2175);
WIRE 16 -1 (-475 2175)(-475 2125);
WIRE 16 -1 (-475 2125)(-225 2125);
WIRE 16 -1 (-475 2125)(-475 2075);
WIRE 16 -1 (-475 2075)(-225 2075);
WIRE 16 -1 (-475 2025)(-225 2025);
WIRE 16 -1 (-475 2075)(-475 2025);
WIRE 16 -1 (-475 2025)(-475 1975);
WIRE 16 -1 (-475 1975)(-225 1975);
WIRE 16 -1 (-475 1975)(-475 1925);
WIRE 16 -1 (-475 1925)(-225 1925);
WIRE 16 -1 (-475 1925)(-475 1875);
WIRE 16 -1 (-475 1875)(-225 1875);
WIRE 16 -1 (-475 1875)(-475 1825);
WIRE 16 -1 (-475 1825)(-225 1825);
WIRE 16 -1 (-475 1825)(-475 1775);
WIRE 16 -1 (-475 1775)(-225 1775);
WIRE 16 -1 (-475 1775)(-475 1725);
WIRE 16 -1 (-225 1725)(-475 1725);
WIRE 16 -1 (-475 1725)(-475 1675);
WIRE 16 -1 (-475 1675)(-225 1675);
WIRE 16 -1 (-475 1675)(-475 1625);
WIRE 16 -1 (-475 1625)(-225 1625);
WIRE 16 -1 (-475 1625)(-475 1575);
WIRE 16 -1 (-475 1575)(-225 1575);
WIRE 16 -1 (-475 1525)(-225 1525);
WIRE 16 -1 (-475 1575)(-475 1525);
WIRE 16 -1 (-475 1525)(-475 1475);
WIRE 16 -1 (-475 1475)(-225 1475);
WIRE 16 -1 (-475 1475)(-475 1425);
WIRE 16 -1 (-475 1425)(-225 1425);
WIRE 16 -1 (-475 1425)(-475 1375);
WIRE 16 -1 (-475 1375)(-225 1375);
WIRE 16 -1 (-475 1375)(-475 1325);
WIRE 16 -1 (-475 1325)(-225 1325);
WIRE 16 -1 (-475 1325)(-475 1275);
WIRE 16 -1 (-475 1275)(-225 1275);
WIRE 16 -1 (-475 1275)(-475 1225);
WIRE 16 -1 (-475 1225)(-225 1225);
WIRE 16 -1 (-475 1225)(-475 1175);
WIRE 16 -1 (-475 1175)(-225 1175);
WIRE 16 -1 (-475 1175)(-475 1125);
WIRE 16 -1 (-475 1125)(-225 1125);
WIRE 16 -1 (-475 1125)(-475 1075);
WIRE 16 -1 (-475 1075)(-225 1075);
WIRE 16 -1 (-475 1075)(-475 1025);
WIRE 16 -1 (-475 1025)(-225 1025);
WIRE 16 -1 (-475 975)(-225 975);
WIRE 16 -1 (-475 1025)(-475 975);
WIRE 16 -1 (-475 975)(-475 925);
WIRE 16 -1 (-475 925)(-225 925);
WIRE 16 -1 (-475 925)(-475 875);
WIRE 16 -1 (-475 875)(-225 875);
WIRE 16 -1 (-475 875)(-475 825);
WIRE 16 -1 (-475 825)(-225 825);
WIRE 16 -1 (-475 825)(-475 775);
WIRE 16 -1 (-475 775)(-225 775);
WIRE 16 -1 (-475 775)(-475 725);
WIRE 16 -1 (-225 725)(-475 725);
WIRE 16 -1 (-475 725)(-475 675);
WIRE 16 -1 (-475 675)(-225 675);
WIRE 16 -1 (-475 675)(-475 625);
WIRE 16 -1 (-475 625)(-225 625);
WIRE 16 -1 (-475 625)(-475 575);
WIRE 16 -1 (-475 575)(-225 575);
WIRE 16 -1 (-475 575)(-475 525);
WIRE 16 -1 (-475 525)(-225 525);
WIRE 16 -1 (-475 475)(-225 475);
WIRE 16 -1 (-475 525)(-475 475);
WIRE 16 -1 (-475 475)(-475 425);
WIRE 16 -1 (-225 425)(-475 425);
WIRE 16 -1 (-475 425)(-475 375);
WIRE 16 -1 (-475 375)(-225 375);
WIRE 16 -1 (-475 375)(-475 325);
WIRE 16 -1 (-475 325)(-225 325);
WIRE 16 -1 (-475 325)(-475 275);
WIRE 16 -1 (-475 275)(-225 275);
WIRE 16 -1 (-475 275)(-475 225);
WIRE 16 -1 (-475 225)(-225 225);
WIRE 16 -1 (-475 225)(-475 175);
WIRE 16 -1 (-475 175)(-225 175);
WIRE 16 -1 (-475 175)(-475 125);
WIRE 16 -1 (-475 125)(-225 125);
WIRE 16 -1 (-475 125)(-475 75);
WIRE 16 -1 (-225 75)(-475 75);
WIRE 16 -1 (-475 75)(-475 25);
WIRE 16 -1 (-475 25)(-225 25);
WIRE 16 -1 (-475 -25)(-225 -25);
WIRE 16 -1 (-475 25)(-475 -25);
WIRE 16 -1 (-475 -25)(-475 -75);
WIRE 16 -1 (-475 -75)(-225 -75);
WIRE 16 -1 (-475 -75)(-475 -125);
WIRE 16 -1 (-475 -125)(-225 -125);
WIRE 16 -1 (2800 3775)(2550 3775);
WIRE 16 -1 (2550 3775)(2550 3725);
WIRE 16 -1 (2800 3725)(2550 3725);
WIRE 16 -1 (2550 3725)(2550 3675);
WIRE 16 -1 (2800 3675)(2550 3675);
WIRE 16 -1 (2550 3675)(2550 3625);
WIRE 16 -1 (2800 3625)(2550 3625);
WIRE 16 -1 (2550 3625)(2550 3575);
WIRE 16 -1 (2800 3575)(2550 3575);
WIRE 16 -1 (2550 3575)(2550 3525);
WIRE 16 -1 (2800 3525)(2550 3525);
WIRE 16 -1 (2550 3525)(2550 3475);
WIRE 16 -1 (2800 3475)(2550 3475);
WIRE 16 -1 (2550 3475)(2550 3425);
WIRE 16 -1 (2800 3425)(2550 3425);
WIRE 16 -1 (2550 3425)(2550 3375);
WIRE 16 -1 (2800 3375)(2550 3375);
WIRE 16 -1 (2550 3375)(2550 3325);
WIRE 16 -1 (2800 3325)(2550 3325);
WIRE 16 -1 (2550 3325)(2550 3275);
WIRE 16 -1 (2800 3275)(2550 3275);
WIRE 16 -1 (2550 3275)(2550 3225);
WIRE 16 -1 (2800 3225)(2550 3225);
WIRE 16 -1 (2550 3225)(2550 3175);
WIRE 16 -1 (2800 3175)(2550 3175);
WIRE 16 -1 (2550 3175)(2550 3125);
WIRE 16 -1 (2800 3125)(2550 3125);
WIRE 16 -1 (2550 3125)(2550 3075);
WIRE 16 -1 (2550 3075)(2800 3075);
WIRE 16 -1 (2550 3025)(2800 3025);
WIRE 16 -1 (2550 3075)(2550 3025);
WIRE 16 -1 (2550 3025)(2550 2975);
WIRE 16 -1 (2550 2975)(2800 2975);
WIRE 16 -1 (2550 2975)(2550 2925);
WIRE 16 -1 (2550 2925)(2800 2925);
WIRE 16 -1 (2550 2925)(2550 2875);
WIRE 16 -1 (2550 2875)(2800 2875);
WIRE 16 -1 (2550 2875)(2550 2825);
WIRE 16 -1 (2550 2825)(2800 2825);
WIRE 16 -1 (2550 2825)(2550 2775);
WIRE 16 -1 (2550 2775)(2800 2775);
WIRE 16 -1 (2550 2775)(2550 2725);
WIRE 16 -1 (2550 2725)(2800 2725);
WIRE 16 -1 (2550 2725)(2550 2675);
WIRE 16 -1 (2550 2675)(2800 2675);
WIRE 16 -1 (2550 2675)(2550 2625);
WIRE 16 -1 (2550 2625)(2800 2625);
WIRE 16 -1 (2550 2625)(2550 2575);
WIRE 16 -1 (2550 2575)(2800 2575);
WIRE 16 -1 (2550 2575)(2550 2525);
WIRE 16 -1 (2550 2525)(2800 2525);
WIRE 16 -1 (2550 2525)(2550 2475);
WIRE 16 -1 (2550 2475)(2800 2475);
WIRE 16 -1 (2550 2475)(2550 2425);
WIRE 16 -1 (2550 2425)(2800 2425);
WIRE 16 -1 (2550 2425)(2550 2375);
WIRE 16 -1 (2550 2375)(2800 2375);
WIRE 16 -1 (2550 2375)(2550 2325);
WIRE 16 -1 (2550 2325)(2800 2325);
WIRE 16 -1 (2550 2325)(2550 2275);
WIRE 16 -1 (2550 2275)(2800 2275);
WIRE 16 -1 (2550 2275)(2550 2225);
WIRE 16 -1 (2550 2225)(2800 2225);
WIRE 16 -1 (2550 2225)(2550 2175);
WIRE 16 -1 (2550 2175)(2800 2175);
WIRE 16 -1 (2550 2175)(2550 2125);
WIRE 16 -1 (2550 2125)(2800 2125);
WIRE 16 -1 (2550 2125)(2550 2075);
WIRE 16 -1 (2550 2075)(2800 2075);
WIRE 16 -1 (2550 2025)(2800 2025);
WIRE 16 -1 (2550 2075)(2550 2025);
WIRE 16 -1 (2550 2025)(2550 1975);
WIRE 16 -1 (2550 1975)(2800 1975);
WIRE 16 -1 (2550 1975)(2550 1925);
WIRE 16 -1 (2550 1925)(2800 1925);
WIRE 16 -1 (2550 1925)(2550 1875);
WIRE 16 -1 (2550 1875)(2800 1875);
WIRE 16 -1 (2550 1875)(2550 1825);
WIRE 16 -1 (2550 1825)(2800 1825);
WIRE 16 -1 (2550 1825)(2550 1775);
WIRE 16 -1 (2550 1775)(2800 1775);
WIRE 16 -1 (2550 1775)(2550 1725);
WIRE 16 -1 (2800 1725)(2550 1725);
WIRE 16 -1 (2550 1725)(2550 1675);
WIRE 16 -1 (2550 1675)(2800 1675);
WIRE 16 -1 (2550 1675)(2550 1625);
WIRE 16 -1 (2550 1625)(2800 1625);
WIRE 16 -1 (2550 1625)(2550 1575);
WIRE 16 -1 (2550 1575)(2800 1575);
WIRE 16 -1 (2550 1575)(2550 1525);
WIRE 16 -1 (2550 1525)(2800 1525);
WIRE 16 -1 (2550 1525)(2550 1475);
WIRE 16 -1 (2550 1475)(2800 1475);
WIRE 16 -1 (2550 1475)(2550 1425);
WIRE 16 -1 (2550 1425)(2800 1425);
WIRE 16 -1 (2550 1425)(2550 1375);
WIRE 16 -1 (2550 1375)(2800 1375);
WIRE 16 -1 (2550 1375)(2550 1325);
WIRE 16 -1 (2550 1325)(2800 1325);
WIRE 16 -1 (2550 1325)(2550 1275);
WIRE 16 -1 (2550 1275)(2800 1275);
WIRE 16 -1 (2550 1275)(2550 1225);
WIRE 16 -1 (2550 1225)(2800 1225);
WIRE 16 -1 (2550 1225)(2550 1175);
WIRE 16 -1 (2550 1175)(2800 1175);
WIRE 16 -1 (2550 1175)(2550 1125);
WIRE 16 -1 (2550 1125)(2800 1125);
WIRE 16 -1 (2550 1125)(2550 1075);
WIRE 16 -1 (2550 1075)(2800 1075);
WIRE 16 -1 (2550 1075)(2550 1025);
WIRE 16 -1 (2550 1025)(2800 1025);
WIRE 16 -1 (2550 975)(2800 975);
WIRE 16 -1 (2550 1025)(2550 975);
WIRE 16 -1 (2550 975)(2550 925);
WIRE 16 -1 (2550 925)(2800 925);
WIRE 16 -1 (2550 925)(2550 875);
WIRE 16 -1 (2550 875)(2800 875);
WIRE 16 -1 (2550 875)(2550 825);
WIRE 16 -1 (2550 825)(2800 825);
WIRE 16 -1 (2550 825)(2550 775);
WIRE 16 -1 (2550 775)(2800 775);
WIRE 16 -1 (2550 775)(2550 725);
WIRE 16 -1 (2800 725)(2550 725);
WIRE 16 -1 (2550 725)(2550 675);
WIRE 16 -1 (2550 675)(2800 675);
WIRE 16 -1 (2550 675)(2550 625);
WIRE 16 -1 (2550 625)(2800 625);
WIRE 16 -1 (2550 625)(2550 575);
WIRE 16 -1 (2550 575)(2800 575);
WIRE 16 -1 (2550 575)(2550 525);
WIRE 16 -1 (2550 525)(2800 525);
WIRE 16 -1 (2550 525)(2550 475);
WIRE 16 -1 (2550 475)(2800 475);
WIRE 16 -1 (2550 475)(2550 425);
WIRE 16 -1 (2800 425)(2550 425);
WIRE 16 -1 (2550 425)(2550 375);
WIRE 16 -1 (2550 375)(2800 375);
WIRE 16 -1 (2550 375)(2550 325);
WIRE 16 -1 (2550 325)(2800 325);
WIRE 16 -1 (2550 325)(2550 275);
WIRE 16 -1 (2550 275)(2800 275);
WIRE 16 -1 (2550 275)(2550 225);
WIRE 16 -1 (2550 225)(2800 225);
WIRE 16 -1 (2550 225)(2550 175);
WIRE 16 -1 (2550 175)(2800 175);
WIRE 16 -1 (2550 175)(2550 125);
WIRE 16 -1 (2550 125)(2800 125);
WIRE 16 -1 (2550 125)(2550 75);
WIRE 16 -1 (2800 75)(2550 75);
WIRE 16 -1 (2550 75)(2550 25);
WIRE 16 -1 (2550 25)(2800 25);
WIRE 16 -1 (2550 -25)(2800 -25);
WIRE 16 -1 (2550 25)(2550 -25);
WIRE 16 -1 (2550 -25)(2550 -75);
WIRE 16 -1 (2550 -75)(2800 -75);
WIRE 16 -1 (2550 -75)(2550 -125);
WIRE 16 -1 (2550 -125)(2800 -125);
WIRE 16 -1 (5450 3775)(5200 3775);
WIRE 16 -1 (5450 3725)(5200 3725);
WIRE 16 -1 (5450 3775)(5450 3725);
WIRE 16 -1 (5450 3675)(5200 3675);
WIRE 16 -1 (5450 3725)(5450 3675);
WIRE 16 -1 (5450 3625)(5200 3625);
WIRE 16 -1 (5450 3675)(5450 3625);
WIRE 16 -1 (5200 3575)(5450 3575);
WIRE 16 -1 (5450 3575)(5450 3625);
WIRE 16 -1 (5450 3525)(5200 3525);
WIRE 16 -1 (5450 3525)(5450 3575);
WIRE 16 -1 (5450 3475)(5200 3475);
WIRE 16 -1 (5450 3525)(5450 3475);
WIRE 16 -1 (5450 3425)(5200 3425);
WIRE 16 -1 (5450 3475)(5450 3425);
WIRE 16 -1 (5450 3375)(5200 3375);
WIRE 16 -1 (5450 3425)(5450 3375);
WIRE 16 -1 (5450 3325)(5200 3325);
WIRE 16 -1 (5450 3375)(5450 3325);
WIRE 16 -1 (5450 3275)(5200 3275);
WIRE 16 -1 (5450 3325)(5450 3275);
WIRE 16 -1 (5450 3225)(5200 3225);
WIRE 16 -1 (5450 3275)(5450 3225);
WIRE 16 -1 (5450 3175)(5200 3175);
WIRE 16 -1 (5450 3225)(5450 3175);
WIRE 16 -1 (5450 3125)(5200 3125);
WIRE 16 -1 (5450 3175)(5450 3125);
WIRE 16 -1 (5200 3075)(5450 3075);
WIRE 16 -1 (5450 3125)(5450 3075);
WIRE 16 -1 (5200 3025)(5450 3025);
WIRE 16 -1 (5450 3075)(5450 3025);
WIRE 16 -1 (5200 2975)(5450 2975);
WIRE 16 -1 (5450 3025)(5450 2975);
WIRE 16 -1 (5200 2925)(5450 2925);
WIRE 16 -1 (5450 2975)(5450 2925);
WIRE 16 -1 (5200 2875)(5450 2875);
WIRE 16 -1 (5450 2925)(5450 2875);
WIRE 16 -1 (5200 2825)(5450 2825);
WIRE 16 -1 (5450 2875)(5450 2825);
WIRE 16 -1 (5200 2775)(5450 2775);
WIRE 16 -1 (5450 2825)(5450 2775);
WIRE 16 -1 (5200 2725)(5450 2725);
WIRE 16 -1 (5450 2725)(5450 2775);
WIRE 16 -1 (5200 2675)(5450 2675);
WIRE 16 -1 (5450 2725)(5450 2675);
WIRE 16 -1 (5450 2625)(5200 2625);
WIRE 16 -1 (5450 2675)(5450 2625);
WIRE 16 -1 (5450 2575)(5200 2575);
WIRE 16 -1 (5450 2625)(5450 2575);
WIRE 16 -1 (5450 2525)(5200 2525);
WIRE 16 -1 (5450 2575)(5450 2525);
WIRE 16 -1 (5450 2475)(5200 2475);
WIRE 16 -1 (5450 2525)(5450 2475);
WIRE 16 -1 (5200 2425)(5450 2425);
WIRE 16 -1 (5450 2425)(5450 2475);
WIRE 16 -1 (5450 2375)(5200 2375);
WIRE 16 -1 (5450 2375)(5450 2425);
WIRE 16 -1 (5450 2325)(5200 2325);
WIRE 16 -1 (5450 2375)(5450 2325);
WIRE 16 -1 (5450 2275)(5200 2275);
WIRE 16 -1 (5450 2325)(5450 2275);
WIRE 16 -1 (5450 2225)(5200 2225);
WIRE 16 -1 (5450 2275)(5450 2225);
WIRE 16 -1 (5450 2175)(5200 2175);
WIRE 16 -1 (5450 2225)(5450 2175);
WIRE 16 -1 (5450 2125)(5200 2125);
WIRE 16 -1 (5450 2175)(5450 2125);
WIRE 16 -1 (5450 2075)(5200 2075);
WIRE 16 -1 (5450 2125)(5450 2075);
WIRE 16 -1 (5450 2025)(5200 2025);
WIRE 16 -1 (5450 2075)(5450 2025);
WIRE 16 -1 (5450 1975)(5200 1975);
WIRE 16 -1 (5450 2025)(5450 1975);
WIRE 16 -1 (5200 1925)(5450 1925);
WIRE 16 -1 (5450 1975)(5450 1925);
WIRE 16 -1 (5200 1875)(5450 1875);
WIRE 16 -1 (5450 1925)(5450 1875);
WIRE 16 -1 (5200 1825)(5450 1825);
WIRE 16 -1 (5450 1875)(5450 1825);
WIRE 16 -1 (5200 1775)(5450 1775);
WIRE 16 -1 (5450 1825)(5450 1775);
WIRE 16 -1 (5200 1725)(5450 1725);
WIRE 16 -1 (5450 1775)(5450 1725);
WIRE 16 -1 (5200 1675)(5450 1675);
WIRE 16 -1 (5450 1725)(5450 1675);
WIRE 16 -1 (5200 1625)(5450 1625);
WIRE 16 -1 (5450 1675)(5450 1625);
WIRE 16 -1 (5200 1575)(5450 1575);
WIRE 16 -1 (5450 1575)(5450 1625);
WIRE 16 -1 (5200 1525)(5450 1525);
WIRE 16 -1 (5450 1575)(5450 1525);
WIRE 16 -1 (5450 1475)(5200 1475);
WIRE 16 -1 (5450 1525)(5450 1475);
WIRE 16 -1 (5450 1425)(5200 1425);
WIRE 16 -1 (5450 1475)(5450 1425);
WIRE 16 -1 (5450 1375)(5200 1375);
WIRE 16 -1 (5450 1425)(5450 1375);
WIRE 16 -1 (5450 1325)(5200 1325);
WIRE 16 -1 (5450 1375)(5450 1325);
WIRE 16 -1 (5200 1275)(5450 1275);
WIRE 16 -1 (5450 1275)(5450 1325);
WIRE 16 -1 (5450 1225)(5200 1225);
WIRE 16 -1 (5450 1225)(5450 1275);
WIRE 16 -1 (5450 1175)(5200 1175);
WIRE 16 -1 (5450 1225)(5450 1175);
WIRE 16 -1 (5450 1125)(5200 1125);
WIRE 16 -1 (5450 1175)(5450 1125);
WIRE 16 -1 (5200 1075)(5450 1075);
WIRE 16 -1 (5450 1125)(5450 1075);
WIRE 16 -1 (5200 1025)(5450 1025);
WIRE 16 -1 (5450 1075)(5450 1025);
WIRE 16 -1 (5200 975)(5450 975);
WIRE 16 -1 (5450 1025)(5450 975);
WIRE 16 -1 (5200 925)(5450 925);
WIRE 16 -1 (5450 975)(5450 925);
WIRE 16 -1 (5200 875)(5450 875);
WIRE 16 -1 (5450 925)(5450 875);
WIRE 16 -1 (5200 825)(5450 825);
WIRE 16 -1 (5450 875)(5450 825);
WIRE 16 -1 (5200 775)(5450 775);
WIRE 16 -1 (5450 825)(5450 775);
WIRE 16 -1 (5200 725)(5450 725);
WIRE 16 -1 (5450 725)(5450 775);
WIRE 16 -1 (5200 675)(5450 675);
WIRE 16 -1 (5450 725)(5450 675);
WIRE 16 -1 (5450 625)(5200 625);
WIRE 16 -1 (5450 675)(5450 625);
WIRE 16 -1 (5450 575)(5200 575);
WIRE 16 -1 (5450 625)(5450 575);
WIRE 16 -1 (5450 525)(5200 525);
WIRE 16 -1 (5450 575)(5450 525);
WIRE 16 -1 (5450 475)(5200 475);
WIRE 16 -1 (5450 525)(5450 475);
WIRE 16 -1 (5200 425)(5450 425);
WIRE 16 -1 (5450 425)(5450 475);
WIRE 16 -1 (5450 375)(5200 375);
WIRE 16 -1 (5450 375)(5450 425);
WIRE 16 -1 (5450 325)(5200 325);
WIRE 16 -1 (5450 375)(5450 325);
WIRE 16 -1 (5450 275)(5200 275);
WIRE 16 -1 (5450 325)(5450 275);
WIRE 16 -1 (5200 225)(5450 225);
WIRE 16 -1 (5450 275)(5450 225);
WIRE 16 -1 (5200 175)(5450 175);
WIRE 16 -1 (5450 225)(5450 175);
WIRE 16 -1 (5200 125)(5450 125);
WIRE 16 -1 (5450 175)(5450 125);
WIRE 16 -1 (5200 75)(5450 75);
WIRE 16 -1 (5450 125)(5450 75);
WIRE 16 -1 (5200 25)(5450 25);
WIRE 16 -1 (5450 75)(5450 25);
WIRE 16 -1 (5200 -25)(5450 -25);
WIRE 16 -1 (5450 25)(5450 -25);
WIRE 16 -1 (5200 -75)(5450 -75);
WIRE 16 -1 (5450 -25)(5450 -75);
WIRE 16 -1 (5450 -125)(5450 -75);
WIRE 16 -1 (5200 -125)(5450 -125);
DOT 1 (2550 3325);
DOT 1 (2550 2225);
DOT 1 (2425 2275);
DOT 1 (2425 2325);
DOT 1 (-625 3275);
DOT 1 (-475 2875);
DOT 1 (-475 1825);
DOT 1 (2550 2875);
DOT 1 (-475 2925);
DOT 1 (-475 2775);
DOT 1 (-475 3275);
DOT 1 (-475 3175);
DOT 1 (-625 1825);
DOT 1 (-3525 -175);
DOT 1 (-3525 -125);
DOT 1 (-3525 -75);
DOT 1 (-3525 -25);
DOT 1 (-3525 75);
DOT 1 (-3525 25);
DOT 1 (-3525 125);
DOT 1 (-625 -175);
DOT 1 (-625 -125);
DOT 1 (-625 -75);
DOT 1 (-625 -25);
DOT 1 (-625 25);
DOT 1 (-625 75);
DOT 1 (-625 125);
DOT 1 (-3525 225);
DOT 1 (-3525 175);
DOT 1 (-3525 275);
DOT 1 (-3525 325);
DOT 1 (-3525 375);
DOT 1 (-3525 425);
DOT 1 (-3525 475);
DOT 1 (-3525 625);
DOT 1 (-3525 525);
DOT 1 (-3525 575);
DOT 1 (-3525 675);
DOT 1 (-3525 725);
DOT 1 (-3525 775);
DOT 1 (-3525 875);
DOT 1 (-3525 825);
DOT 1 (-3525 925);
DOT 1 (-3525 975);
DOT 1 (-3525 1025);
DOT 1 (-3525 1075);
DOT 1 (-3525 1125);
DOT 1 (-3525 1275);
DOT 1 (-3525 1175);
DOT 1 (-3525 1225);
DOT 1 (-3525 1325);
DOT 1 (-3525 1375);
DOT 1 (-3525 1425);
DOT 1 (-3525 1475);
DOT 1 (-3525 1525);
DOT 1 (-3525 1625);
DOT 1 (-3525 1575);
DOT 1 (-3525 1675);
DOT 1 (-3525 1725);
DOT 1 (-3525 1775);
DOT 1 (-3525 1825);
DOT 1 (-3525 1875);
DOT 1 (-3525 1925);
DOT 1 (-3525 2025);
DOT 1 (-3525 1975);
DOT 1 (-3525 2125);
DOT 1 (-3525 2075);
DOT 1 (-3525 2175);
DOT 1 (-3525 2225);
DOT 1 (-3525 2275);
DOT 1 (-3525 2325);
DOT 1 (-3525 2375);
DOT 1 (-3525 2425);
DOT 1 (-3525 2475);
DOT 1 (-3525 2525);
DOT 1 (-3525 2575);
DOT 1 (-3525 2625);
DOT 1 (-3525 2675);
DOT 1 (-3525 2725);
DOT 1 (-3525 2775);
DOT 1 (-3525 2825);
DOT 1 (-3525 2875);
DOT 1 (-3525 2925);
DOT 1 (-3525 2975);
DOT 1 (-3525 3025);
DOT 1 (-3525 3075);
DOT 1 (-3525 3125);
DOT 1 (-3525 3175);
DOT 1 (-3525 3275);
DOT 1 (-3525 3225);
DOT 1 (-3525 3325);
DOT 1 (-3525 3425);
DOT 1 (-3525 3375);
DOT 1 (-3525 3575);
DOT 1 (-3525 3525);
DOT 1 (-3525 3475);
DOT 1 (-3525 3675);
DOT 1 (-3525 3625);
DOT 1 (-3525 3725);
DOT 1 (-625 225);
DOT 1 (-625 175);
DOT 1 (-625 275);
DOT 1 (-625 325);
DOT 1 (-625 375);
DOT 1 (-625 475);
DOT 1 (-625 425);
DOT 1 (-625 525);
DOT 1 (-625 575);
DOT 1 (-625 625);
DOT 1 (-625 675);
DOT 1 (-625 725);
DOT 1 (-625 775);
DOT 1 (-625 825);
DOT 1 (-625 875);
DOT 1 (-625 975);
DOT 1 (-625 925);
DOT 1 (-625 1025);
DOT 1 (-625 1075);
DOT 1 (-625 1125);
DOT 1 (-625 1175);
DOT 1 (-625 1225);
DOT 1 (-625 1275);
DOT 1 (-625 1325);
DOT 1 (-625 1375);
DOT 1 (-625 1425);
DOT 1 (-625 1475);
DOT 1 (-625 1525);
DOT 1 (-625 1575);
DOT 1 (-625 1625);
DOT 1 (-625 1675);
DOT 1 (-625 1725);
DOT 1 (-625 1775);
DOT 1 (-625 1875);
DOT 1 (-625 1925);
DOT 1 (-625 1975);
DOT 1 (-625 2025);
DOT 1 (-625 2075);
DOT 1 (-625 2125);
DOT 1 (-625 2175);
DOT 1 (-625 2225);
DOT 1 (-625 2275);
DOT 1 (-625 2325);
DOT 1 (-625 2375);
DOT 1 (-625 2425);
DOT 1 (-625 2475);
DOT 1 (-625 2525);
DOT 1 (-625 2575);
DOT 1 (-625 2625);
DOT 1 (-625 2675);
DOT 1 (-625 2775);
DOT 1 (-625 2725);
DOT 1 (-625 2825);
DOT 1 (-625 2875);
DOT 1 (-625 2925);
DOT 1 (-625 2975);
DOT 1 (-625 3025);
DOT 1 (-625 3075);
DOT 1 (-625 3125);
DOT 1 (-625 3175);
DOT 1 (-625 3325);
DOT 1 (-625 3225);
DOT 1 (-625 3375);
DOT 1 (-625 3425);
DOT 1 (-625 3475);
DOT 1 (-625 3525);
DOT 1 (-625 3575);
DOT 1 (-625 3625);
DOT 1 (-625 3675);
DOT 1 (-625 3725);
DOT 1 (-475 -175);
DOT 1 (-475 -125);
DOT 1 (-475 -75);
DOT 1 (-475 -25);
DOT 1 (-475 25);
DOT 1 (-475 75);
DOT 1 (-475 125);
DOT 1 (2425 -175);
DOT 1 (2425 -125);
DOT 1 (2425 -75);
DOT 1 (2425 -25);
DOT 1 (2425 25);
DOT 1 (2425 125);
DOT 1 (2425 75);
DOT 1 (2550 -175);
DOT 1 (2550 -125);
DOT 1 (2550 -25);
DOT 1 (2550 -75);
DOT 1 (2550 25);
DOT 1 (2550 75);
DOT 1 (2550 125);
DOT 1 (5450 -175);
DOT 1 (5450 -125);
DOT 1 (5450 25);
DOT 1 (5450 -25);
DOT 1 (5450 -75);
DOT 1 (5450 75);
DOT 1 (5450 125);
DOT 1 (-475 225);
DOT 1 (-475 175);
DOT 1 (-475 275);
DOT 1 (-475 325);
DOT 1 (-475 375);
DOT 1 (-475 475);
DOT 1 (-475 425);
DOT 1 (-475 525);
DOT 1 (-475 575);
DOT 1 (-475 625);
DOT 1 (-475 725);
DOT 1 (-475 675);
DOT 1 (-475 775);
DOT 1 (-475 825);
DOT 1 (-475 875);
DOT 1 (-475 975);
DOT 1 (-475 925);
DOT 1 (-475 1025);
DOT 1 (-475 1075);
DOT 1 (-475 1125);
DOT 1 (-475 1175);
DOT 1 (-475 1225);
DOT 1 (-475 1275);
DOT 1 (-475 1325);
DOT 1 (-475 1375);
DOT 1 (-475 1425);
DOT 1 (-475 1475);
DOT 1 (-475 1525);
DOT 1 (-475 1625);
DOT 1 (-475 1575);
DOT 1 (-475 1725);
DOT 1 (-475 1675);
DOT 1 (-475 1775);
DOT 1 (-475 1875);
DOT 1 (-475 1925);
DOT 1 (-475 1975);
DOT 1 (-475 2025);
DOT 1 (-475 2075);
DOT 1 (-475 2125);
DOT 1 (-475 2175);
DOT 1 (-475 2225);
DOT 1 (-475 2275);
DOT 1 (-475 2325);
DOT 1 (-475 2375);
DOT 1 (-475 2425);
DOT 1 (-475 2525);
DOT 1 (-475 2475);
DOT 1 (-475 2575);
DOT 1 (-475 2625);
DOT 1 (-475 2675);
DOT 1 (-475 2725);
DOT 1 (-475 2825);
DOT 1 (-475 3025);
DOT 1 (-475 2975);
DOT 1 (-475 3075);
DOT 1 (-475 3125);
DOT 1 (-475 3325);
DOT 1 (-475 3225);
DOT 1 (-475 3375);
DOT 1 (-475 3425);
DOT 1 (-475 3525);
DOT 1 (-475 3575);
DOT 1 (-475 3625);
DOT 1 (-475 3675);
DOT 1 (-475 3725);
DOT 1 (2425 225);
DOT 1 (2425 175);
DOT 1 (2425 275);
DOT 1 (2425 325);
DOT 1 (2425 375);
DOT 1 (2425 425);
DOT 1 (2425 475);
DOT 1 (2425 525);
DOT 1 (2425 625);
DOT 1 (2425 575);
DOT 1 (2425 725);
DOT 1 (2425 675);
DOT 1 (2425 775);
DOT 1 (2425 825);
DOT 1 (2425 875);
DOT 1 (2425 925);
DOT 1 (2425 975);
DOT 1 (2425 1025);
DOT 1 (2425 1125);
DOT 1 (2425 1075);
DOT 1 (2425 1175);
DOT 1 (2425 1225);
DOT 1 (2425 1275);
DOT 1 (2425 1325);
DOT 1 (2425 1375);
DOT 1 (2425 1425);
DOT 1 (2425 1475);
DOT 1 (2425 1525);
DOT 1 (2425 1575);
DOT 1 (2425 1625);
DOT 1 (2425 1675);
DOT 1 (2425 1725);
DOT 1 (2425 1775);
DOT 1 (2425 1825);
DOT 1 (2425 1875);
DOT 1 (2425 1925);
DOT 1 (2425 1975);
DOT 1 (2425 2025);
DOT 1 (2425 2075);
DOT 1 (2425 2125);
DOT 1 (2550 225);
DOT 1 (2550 175);
DOT 1 (2550 275);
DOT 1 (2550 325);
DOT 1 (2550 375);
DOT 1 (2550 425);
DOT 1 (2550 475);
DOT 1 (2550 625);
DOT 1 (2550 525);
DOT 1 (2550 575);
DOT 1 (2550 675);
DOT 1 (2550 725);
DOT 1 (2550 775);
DOT 1 (2550 875);
DOT 1 (2550 825);
DOT 1 (2550 925);
DOT 1 (2550 975);
DOT 1 (2550 1025);
DOT 1 (2550 1075);
DOT 1 (2550 1125);
DOT 1 (2550 1275);
DOT 1 (2550 1225);
DOT 1 (2550 1175);
DOT 1 (2550 1375);
DOT 1 (2550 1325);
DOT 1 (2550 1525);
DOT 1 (2550 1475);
DOT 1 (2550 1425);
DOT 1 (2550 1575);
DOT 1 (2550 1625);
DOT 1 (2550 1675);
DOT 1 (2550 1725);
DOT 1 (2550 1775);
DOT 1 (2550 1825);
DOT 1 (2550 1875);
DOT 1 (2550 1925);
DOT 1 (2550 1975);
DOT 1 (2550 2025);
DOT 1 (2550 2075);
DOT 1 (2550 2125);
DOT 1 (2425 2175);
DOT 1 (2550 2175);
DOT 1 (2425 2225);
DOT 1 (2425 2375);
DOT 1 (2425 2425);
DOT 1 (2425 2475);
DOT 1 (2425 2525);
DOT 1 (2425 2575);
DOT 1 (2425 2675);
DOT 1 (2425 2625);
DOT 1 (2425 2775);
DOT 1 (2425 2725);
DOT 1 (2425 2825);
DOT 1 (2425 2875);
DOT 1 (2425 2925);
DOT 1 (2425 2975);
DOT 1 (2425 3025);
DOT 1 (2425 3075);
DOT 1 (2425 3125);
DOT 1 (2425 3175);
DOT 1 (2425 3225);
DOT 1 (2425 3275);
DOT 1 (2425 3325);
DOT 1 (2425 3375);
DOT 1 (2425 3425);
DOT 1 (2425 3475);
DOT 1 (2425 3525);
DOT 1 (2425 3575);
DOT 1 (2425 3625);
DOT 1 (2425 3675);
DOT 1 (2425 3725);
DOT 1 (2550 2275);
DOT 1 (2550 2325);
DOT 1 (2550 2375);
DOT 1 (2550 2425);
DOT 1 (2550 2475);
DOT 1 (2550 2525);
DOT 1 (2550 2575);
DOT 1 (2550 2625);
DOT 1 (2550 2675);
DOT 1 (2550 2725);
DOT 1 (2550 2775);
DOT 1 (2550 2825);
DOT 1 (2550 2925);
DOT 1 (2550 2975);
DOT 1 (2550 3025);
DOT 1 (2550 3075);
DOT 1 (2550 3125);
DOT 1 (2550 3175);
DOT 1 (2550 3275);
DOT 1 (2550 3225);
DOT 1 (2550 3425);
DOT 1 (2550 3475);
DOT 1 (2550 3525);
DOT 1 (2550 3575);
DOT 1 (2550 3625);
DOT 1 (2550 3675);
DOT 1 (2550 3725);
DOT 1 (5450 325);
DOT 1 (5450 375);
DOT 1 (5450 175);
DOT 1 (5450 225);
DOT 1 (5450 275);
DOT 1 (5450 575);
DOT 1 (5450 525);
DOT 1 (5450 425);
DOT 1 (5450 475);
DOT 1 (5450 625);
DOT 1 (5450 825);
DOT 1 (5450 775);
DOT 1 (5450 725);
DOT 1 (5450 675);
DOT 1 (5450 875);
DOT 1 (5450 1075);
DOT 1 (5450 1025);
DOT 1 (5450 925);
DOT 1 (5450 975);
DOT 1 (5450 1125);
DOT 1 (5450 1325);
DOT 1 (5450 1275);
DOT 1 (5450 1175);
DOT 1 (5450 1225);
DOT 1 (5450 1375);
DOT 1 (5450 1575);
DOT 1 (5450 1525);
DOT 1 (5450 1475);
DOT 1 (5450 1425);
DOT 1 (5450 1625);
DOT 1 (5450 1825);
DOT 1 (5450 1775);
DOT 1 (5450 1725);
DOT 1 (5450 1675);
DOT 1 (5450 1875);
DOT 1 (5450 1925);
DOT 1 (5450 2075);
DOT 1 (5450 2025);
DOT 1 (5450 1975);
DOT 1 (5450 2125);
DOT 1 (5450 2175);
DOT 1 (5450 2325);
DOT 1 (5450 2275);
DOT 1 (5450 2225);
DOT 1 (5450 2375);
DOT 1 (5450 2425);
DOT 1 (5450 2625);
DOT 1 (5450 2575);
DOT 1 (5450 2525);
DOT 1 (5450 2475);
DOT 1 (5450 2675);
DOT 1 (5450 2875);
DOT 1 (5450 2825);
DOT 1 (5450 2725);
DOT 1 (5450 2775);
DOT 1 (5450 2925);
DOT 1 (5450 3075);
DOT 1 (5450 3175);
DOT 1 (5450 3025);
DOT 1 (5450 2975);
DOT 1 (5450 3125);
DOT 1 (5450 3375);
DOT 1 (5450 3275);
DOT 1 (5450 3225);
DOT 1 (5450 3325);
DOT 1 (5450 3425);
DOT 1 (5450 3625);
DOT 1 (5450 3575);
DOT 1 (5450 3525);
DOT 1 (5450 3475);
DOT 1 (5450 3675);
DOT 1 (5450 3725);
DOT 1 (-475 3475);
DOT 1 (2550 3375);
QUIT
